P  JOB   G:/<user>/Board/TO/9054_F0T_PDB_BD_GPU_F_V04_1213_1550.brd                
P  CODE  00                                                                     
P  UNITS CUST 0                                                                 
P  TITLE G:/<user>/Board/TO/9054_F0T_PDB_BD_GPU_F_V04_1213_1550.brd                
P  NUM   001                                                                    
P  REV   A                                                                      
P  VER IPC-D-356A                                                               
C                                                                               
C  IPC-D-356 Ouptut File from Allegro                                           
C  IPC File Date: Thu Dec 15 15:17:20 2022                                      
C                                                                               
C                                                                               
C  Board File:             9054_F0T_PDB_BD_GPU_F_V04_1213_1550.brd              
C  Design Rule Status:     UP TO DATE                                           
C  Unit of Measure:        mils                                                 
C  Decimal Place Accuracy: 2                                                    
C  Number of etch Layers:  10                                                   
C  Board Thickness(mils):  92.900000                                            
C  Drawing Extents(mils):  -500000  -2000000  4700000  3700000                  
C                                                                               
C                                                                               
C  BOARD LAYER INFORMATION                                                      
C                                                                               
C     Layer      Layer            Layer             Film  Layer                 
C     Name       Material         Type              Type  Number                
C  ---------------------------------------------------------                    
C  TOP           COPPER           CONDUCTOR         POS     1                   
C  GND           COPPER           PLANE             NEG     2                   
C  IN1           COPPER           CONDUCTOR         POS     3                   
C  GND1          COPPER           PLANE             NEG     4                   
C  VCC           COPPER           PLANE             NEG     5                   
C  VCC1          COPPER           PLANE             NEG     6                   
C  GND2          COPPER           PLANE             NEG     7                   
C  IN2           COPPER           CONDUCTOR         POS     8                   
C  GND3          COPPER           PLANE             NEG     9                   
C  BOTTOM        COPPER           CONDUCTOR         POS    10                   
C                                                                               
C                                                                               
C  PADSTACK INFORMATION                                                         
C                                                                               
C     Padstack          First     Last                                          
C     Name              Layer     Layer     Width     Height                    
C  ---------------------------------------------------------                    
C  SMD17X24             TOP       TOP            2100      2800                 
C  C400D252B394X670IY-1 TOP       BOTTOM        40400     67679                 
C  C315D167B315I237_NPT TOP       BOTTOM        31900     31900                 
C  VIA18D10A26_BGA      TOP       BOTTOM         2600      2600                 
C  SMD37X50_CUT         TOP       TOP            4042      5322                 
C  SMD10X50             TOP       TOP            1400      5400                 
C  SMD10X32             TOP       TOP            1400      3600                 
C  SMD10X34_CUT         TOP       TOP            1384      3746                 
C  VT20D10B20           TOP       BOTTOM         7502      7500                 
C  SPD_C125                                     12500     12500                 
C  SMD32X34             TOP       TOP            3600      3800                 
C  SMD15X46             TOP       TOP            1900      5000                 
C  SMD144X213_CUT       TOP       TOP           14770     21660                 
C  SMD11X28             TOP       TOP            1500      3200                 
C  SMD11X30             TOP       TOP            1500      3400                 
C  SMD42X99             TOP       TOP            4600     10300                 
C  C61D41               TOP       BOTTOM         7100      7100                 
C  C86D86N_T1-18        TOP       BOTTOM        11600     11600                 
C  SMD63X119            TOP       TOP            6700     12300                 
C  SMD128X138           TOP       TOP           13200     14200                 
C  SMD67X99             TOP       TOP            7100     10300                 
C  SMD85X89             TOP       TOP            8900      9300                 
C  SH32X124_SM32X124_CU TOP       TOP            3150     12402                 
C  SMD12X79             TOP       TOP            1600      8300                 
C  SH0-3X0-9_CUT        TOP       TOP            3944      1582                 
C  SMD12X32             TOP       TOP            1600      3600                 
C  SMD7X32              TOP       TOP            1100      3600                 
C  SMD18X20             TOP       TOP            2200      2400                 
C  C70D50               TOP       BOTTOM         8000      8000                 
C  S70D50               TOP       BOTTOM         8000      8000                 
C  SMD63X138            TOP       TOP            6700     14200                 
C  SMD24X32             TOP       TOP            2800      3600                 
C  SMD18X52             TOP       TOP            2200      5600                 
C  SMD22X32             TOP       TOP            2600      3600                 
C  OB74X123D64X113_T2_N TOP       BOTTOM         9400     14300                 
C  C414D203_T2_NPM_ANT4 TOP       BOTTOM        41800     41800                 
C  RE-R_0824-2          TOP       TOP            2384      2368                 
C  RE-L_0824-2          TOP       TOP            2384      2368                 
C  SMD128X135           TOP       TOP           13200     13900                 
C  SMD32X36             TOP       TOP            3600      4000                 
C  SMD22X68             TOP       TOP            2600      7200                 
C  SMD14X59             TOP       TOP            1800      6300                 
C  SMD14X56             TOP       TOP            1800      6000                 
C  SMD40X63             TOP       TOP            4400      6700                 
C  SMD110X220           TOP       TOP           11400     22400                 
C  SMD59X134            TOP       TOP            6300     13800                 
C  SMDOB12X33_SM14X37   TOP       TOP            1400      3700                 
C  SMD10X20             TOP       TOP            1400      2400                 
C  SMD126X270           TOP       TOP           13000     27400                 
C  SMD44X54             TOP       TOP            4800      5800                 
C  SMD52X122_PM48X119_C TOP       TOP            5600     12600                 
C  SH8-45X10-6_PM8-35X1 TOP       TOP           33668     42132                 
C  SH28X32_NPM          TOP       TOP            3200      7600                 
C  SMD28X32_NPM         TOP       TOP            3200      3600                 
C  SMD28X32             TOP       TOP            3200      3600                 
C  SMD46X62             TOP       TOP            5000      6600                 
C  SMD40X50             TOP       TOP            4400      5400                 
C  C66D46               TOP       BOTTOM         7600      7600                 
C  S66D46               TOP       BOTTOM         7600      7600                 
C  S60-15D40-15_FIT     TOP       BOTTOM         6415      6415                 
C  C60-15D40-15_FIT     TOP       BOTTOM         6415      6415                 
C  C256D126N_V166_ANT25 TOP       BOTTOM        26000     26000                 
C  C85D85N              TOP       BOTTOM        11502     11502                 
C  C95D95N              TOP       BOTTOM        12500     12500                 
C  C85D67_SM85_NPM      TOP       BOTTOM         9700      9700                 
C  C45-52D29-52_T1-96_F TOP       BOTTOM         4952      4952                 
C  S45-52D29-52_T1-96_F TOP       BOTTOM         4952      4952                 
C  C83D83N_T1-96_0      TOP       BOTTOM        11300     11300                 
C  C125D125N_T2-0       TOP       BOTTOM        15500     15500                 
C  C158D158N            TOP       BOTTOM        18800     18800                 
C  GHC30D22_NTH         TOP       BOTTOM         4200      4200                 
C  OB355X552D119_197OB1 TOP       BOTTOM        35900     55600                 
C  SMD99X130            TOP       TOP           10300     13400                 
C  SMD95X130            TOP       TOP            9900     13400                 
C  SMD24X28             TOP       TOP            2800      3200                 
C  VT20D10T30           TOP       BOTTOM         7502      7500                 
C  VT20D10B26           TOP       BOTTOM         7502      7500                 
C  VIA20D10             TOP       BOTTOM         3000      3000                 
C  SMDC39M118           TOP       TOP           11800     11800                 
C  TP26B                BOTTOM    BOTTOM         7500      7500                 
C  TP30T                TOP       TOP            7500      7500                 
C                                                                               
C                                                                               
C  ****************************************                                     
C     Name mapping for long Signal names                                        
C  ****************************************                                     
C                                                                               
P  NNAMEm0000 FM_HS2_EN_FUSE_BUF                                                
P  NNAMEm0001 FM_HS2_EN_BUSBAR_BUF                                              
P  NNAMEm0002 FM_HS1_EN_FUSE_BUF                                                
P  NNAMEm0003 FM_HS1_EN_BUSBAR_BUF                                              
P  NNAMEm0004 P12V_LED_EN_BUF                                                   
P  NNAMEm0005 P3V3_HPDB_PG_R1                                                   
P  NNAMEm0006 FAN_PWR_EN_BUF_R                                                  
P  NNAMEm0007 SMB_IOEXP_2_SCL                                                   
P  NNAMEm0008 SMB_IOEXP_2_SDA                                                   
P  NNAMEm0009 PWRGD_P12V_FAN_LED_R                                              
P  NNAMEm0010 PWRGD_P3V3_HPDB_R                                                 
P  NNAMEm0011 PWRGD_P3V3_HPDB                                                   
P  NNAMEm0012 PRSNT_FAN_BP1_N                                                   
P  NNAMEm0013 PRSNT_FAN_BP0_N                                                   
P  NNAMEm0014 P12V_LED_ISET_R                                                   
P  NNAMEm0015 PWRGD_P12V_FAN_LED                                                
P  NNAMEm0016 PWRGD_P3V3_HPDB_R_N                                               
P  NNAMEm0017 PWRGD_P52V_HS2_PG                                                 
P  NNAMEm0018 PWRGD_P52V_HS1_PG                                                 
P  NNAMEm0019 PRSNT_FAN_BP0_R_N                                                 
P  NNAMEm0020 PRSNT_FAN_BP1_R_N                                                 
P  NNAMEm0021 FM_HS1_EN_BUSBAR                                                  
P  NNAMEm0022 FM_HS2_EN_BUSBAR                                                  
P  NNAMEm0023 SMB_P52V_PDB_SCL_R1                                               
P  NNAMEm0024 SMB_P52V_PDB_SCL_R2                                               
P  NNAMEm0025 GND1_FIELD_SIGNAL                                                 
P  NNAMEm0026 PWRGD_P52V_HS2_4287_PG_N                                          
P  NNAMEm0027 PWRGD_P52V_HS_PG_R2                                               
P  NNAMEm0028 P52V_HS2_SENSE_P_R2                                               
P  NNAMEm0029 P52V_HS2_TEMPN_R                                                  
P  NNAMEm0030 P52V_HS2_SENSE_N_R2                                               
P  NNAMEm0031 P52V_HS2_DRAIN_1                                                  
P  NNAMEm0032 P52V_HS2_DRAIN_2                                                  
P  NNAMEm0033 P52V_HS1_UVLO_EN                                                  
P  NNAMEm0034 SMB_CM_HS2_3V3SB_DATI                                             
P  NNAMEm0035 P52V_HS2_ESTART                                                   
P  NNAMEm0036 SMB_CM_HS1_3V3SB_DATO                                             
P  NNAMEm0037 P52V_HS2_EFAULT_R                                                 
P  NNAMEm0038 SMB_CM_HS2_3V3SB_DATO                                             
P  NNAMEm0039 P52V_HS2_ISTART                                                   
P  NNAMEm0040 SMB_CM_HS1_3V3SB_DATI                                             
P  NNAMEm0041 P52V_HS2_ESTART_R                                                 
P  NNAMEm0042 P52V_HS2_EFAULT                                                   
P  NNAMEm0043 P52V_HS1_EFAULT_R                                                 
P  NNAMEm0044 P52V_HS2_PWRGIN                                                   
P  NNAMEm0045 P52V_HS1_ESTART                                                   
P  NNAMEm0046 P52V_HS2_DV_DT_R                                                  
P  NNAMEm0047 P52V_HS1_ESTART_R                                                 
P  NNAMEm0048 P52V_HS2_1272_S_N                                                 
P  NNAMEm0049 P52V_HS1_EFAULT                                                   
P  NNAMEm0050 P52V_HS2_1272_S_P                                                 
P  NNAMEm0051 P52V_HS1_ISTART                                                   
P  NNAMEm0052 P52V_HS2_1272_GATE                                                
P  NNAMEm0053 P52V_HS1_DV_DT_R                                                  
P  NNAMEm0054 P52V_HS1_PWRGIN                                                   
P  NNAMEm0055 P52V_HS2_4287_GATE2_RC                                            
P  NNAMEm0056 P52V_HS2_GATE2_R1                                                 
P  NNAMEm0057 P52V_HS2_4287_S2P                                                 
P  NNAMEm0058 P52V_HS2_4287_GATE_R                                              
P  NNAMEm0059 P52V_HS2_4287_S1P                                                 
P  NNAMEm0060 SMB_P52V_PDB_SCL_R4                                               
P  NNAMEm0061 P52V_HS2_UVLO_EN                                                  
P  NNAMEm0062 P52V_HS2_4287_ADC_N                                               
P  NNAMEm0063 P52V_HS2_4287_S2N                                                 
P  NNAMEm0064 P52V_HS2_4287_S1N                                                 
P  NNAMEm0065 P52V_HS2_4287_GATE2_R                                             
P  NNAMEm0066 P52V_HS2_4287_ADC_P                                               
P  NNAMEm0067 P52V_HS2_GATE2_R                                                  
P  NNAMEm0068 P52V_HS2_GATE1_R                                                  
P  NNAMEm0069 P52V_HS1_DRAIN_1                                                  
P  NNAMEm0070 P52V_HS_4287_S2P                                                  
P  NNAMEm0071 P52V_HS1_4287_GATE2_R                                             
P  NNAMEm0072 P52V_HS1_GATE2_R                                                  
P  NNAMEm0073 P52V_HS_1272_S_P                                                  
P  NNAMEm0074 P52V_HS_4287_ADC_P                                                
P  NNAMEm0075 P52V_HS_1272_S_N                                                  
P  NNAMEm0076 P52V_HS1_TEMPN_R                                                  
P  NNAMEm0077 P52V_HS_4287_ADC_N                                                
P  NNAMEm0078 P52V_HS1_DRAIN_2                                                  
P  NNAMEm0079 P52V_HS1_GATE1_R                                                  
P  NNAMEm0080 P52V_HS1_SENSE_N_R2                                               
P  NNAMEm0081 P52V_HS1_4287_GATE_R                                              
P  NNAMEm0082 P52V_HS1_1272_GATE                                                
P  NNAMEm0083 P52V_HS_4287_S2N                                                  
P  NNAMEm0084 P52V_HS_4287_S1N                                                  
P  NNAMEm0085 P52V_HS_4287_S1P                                                  
P  NNAMEm0086 P52V_HS1_SENSE_P_R2                                               
P  NNAMEm0087 SMB_P52V_PDB_SCL_R3                                               
P  NNAMEm0088 P52V_HS1_4287_GATE2_RC                                            
P  NNAMEm0089 P52V_HS1_GATE2_R1                                                 
P  NNAMEm0090 P52V_HS1_GATE_R1                                                  
P  NNAMEm0091 P52V_HS1_INTVCC                                                   
P  NNAMEm0092 GND_FIELD_SIGNAL                                                  
P  NNAMEm0093 P52V_HS1_TEMP_R                                                   
P  NNAMEm0094 P52V_HS2_GATE_RC                                                  
P  NNAMEm0095 P52V_HS1_GATE_RC                                                  
P  NNAMEm0096 SMB_P52V_HS1_SDAO                                                 
P  NNAMEm0097 SMB_P52V_HS1_SDAI                                                 
P  NNAMEm0098 SMB_P52V_HS2_SDAO                                                 
P  NNAMEm0099 SMB_P52V_HS2_SDAI                                                 
P  NNAMEm0100 P52V_HS2_TEMP_R                                                   
P  NNAMEm0101 P52V_HS2_GATE_R1                                                  
P  NNAMEm0102 P52V_HS2_INTVCC                                                   
P  NNAMEm0103 PWRGD_P52V_HS2_4287_PG_R_N                                        
P  NNAMEm0104 PWRGD_P52V_HS1_4287_PG_R_N                                        
P  NNAMEm0105 PWRGD_P52V_HS1_4287_PG_N                                          
P  NNAMEm0106 P12V_HPDB_PWRGD                                                   
P  NNAMEm0107 SW_P3V3_HPDB_FLT                                                  
P  NNAMEm0108 SW_P3V3_HPDB_PH                                                   
P  NNAMEm0109 SW_P3V3_HPDB_BT_R                                                 
P  NNAMEm0110 SW_P3V3_HPDB_BT                                                   
P  NNAMEm0111 SMB_PDB_MISC_SCL_R1                                               
P  NNAMEm0112 PWRGD_P3V3_AUX_MB_BUF_N                                           
P  NNAMEm0113 GPU_HSC2_BUF_EN_N                                                 
P  NNAMEm0114 GPU_HSC1_BUF_EN_N                                                 
P  NNAMEm0115 GPU_HSC_BUF_R_EN                                                  
P  NNAMEm0116 GPU_HSC2_BUF_EN                                                   
P  NNAMEm0117 GPU_HSC1_BUF_EN                                                   
P  NNAMEm0118 PWRGD_P52V_HS_PG                                                  
P  NNAMEm0119 P52V_HS1_EN_DISCHARGE_VBE_R                                       
P  NNAMEm0120 P52V_HS1_EN_DISCHARGE_VBE                                         
P  NNAMEm0121 P52V_HS1_EN_DISCHARGE_N                                           
P  NNAMEm0122 P52V_HS1_EN_DISCHARGE                                             
P  NNAMEm0123 TP_9543_FAN_INT_N                                                 
P  NNAMEm0124 P52V_HS2_EN_DISCHARGE_VBE_R                                       
P  NNAMEm0125 P52V_HS2_EN_DISCHARGE                                             
P  NNAMEm0126 P52V_HS2_EN_DISCHARGE_N                                           
P  NNAMEm0127 P52V_HS2_EN_DISCHARGE_VBE                                         
P  NNAMEm0128 SMB_PDB_FAN_0_R_SDA                                               
P  NNAMEm0129 SMB_PDB_FAN_0_R_SCL                                               
P  NNAMEm0130 PWRGD_P52V_HS1_4287_PG                                            
P  NNAMEm0131 P52V_HS1_SENSE_P_R1                                               
P  NNAMEm0132 P52V_HS1_SENSE_N_R1                                               
P  NNAMEm0133 TDR_SE_50_OHM_IN2                                                 
P  NNAMEm0134 TDR_SE_50_OHM_BOT                                                 
P  NNAMEm0135 TDR_SE_50_OHM_TOP                                                 
P  NNAMEm0136 TDR_SE_50_OHM_IN1                                                 
P  NNAMEm0137 SMB_P52V_PDB_SDA_R                                                
P  NNAMEm0138 SMB_P52V_PDB_SCL_R                                                
P  NNAMEm0139 SMB_P52V_PDB_SCL                                                  
P  NNAMEm0140 SMB_P52V_PDB_SDA                                                  
P  NNAMEm0141 RST_SMB_PDB_BUF_N                                                 
P  NNAMEm0142 P52V_HS2_SENSE_P_R1                                               
P  NNAMEm0143 RST_SMB_FAN_1_R_N                                                 
P  NNAMEm0144 SMB_PDB_FAN_0_SDA                                                 
P  NNAMEm0145 SMB_PDB_FAN_1_R_SDA                                               
P  NNAMEm0146 SMB_PDB_FAN_1_R_SCL                                               
P  NNAMEm0147 SMB_FAN_MUX_SCL                                                   
P  NNAMEm0148 SMB_PDB_FAN_1_SDA                                                 
P  NNAMEm0149 P52V_HS2_SENSE_N_R1                                               
P  NNAMEm0150 SMB_FAN_MUX_SDA                                                   
P  NNAMEm0151 SMB_PDB_FAN_0_SCL                                                 
P  NNAMEm0152 SMB_P52V_PDB_DEBUG_SCL                                            
P  NNAMEm0153 SMB_PDB_FAN_1_SCL                                                 
P  NNAMEm0154 SMB_P52V_PDB_DEBUG_SDA                                            
P  NNAMEm0155 PWRGD_P52V_HS2_4287_PG                                            
P  NNAMEm0156 SMB_PDB_MISC_SCL                                                  
P  NNAMEm0157 PWRGD_P3V3_AUX_MB_BUF                                             
P  NNAMEm0158 SMB_PDB_MISC_SDA_R                                                
P  NNAMEm0159 SMB_PDB_MISC_SCL_R                                                
P  NNAMEm0160 SMB_PDB_MISC_SDA                                                  
P  NNAMEm0161 RST_SMB_FAN_0_R_N                                                 
C                                                                               
C  ****************************************                                     
C      SIGNAL PINS & VIAS ON THE BOARD                                          
C  ****************************************                                     
C                                                                               
327TP_U8_P07        U8    -11         A01X+164350Y+015548X0140Y0590R270 S1      
317TP_U8_P07        VIA   -           A01X+166000Y+019350X0200Y         S2      
017TP_U8_P07        VIA   -           A10X+166000Y+019350X0260Y         S2      
017TP_U8_P07              -     D0100PA00X+166000Y+019350                       
327TP_U8_P05        U8    -9          A01X+164350Y+016060X0140Y0590R270 S1      
317TP_U8_P05        VIA   -           A01X+165400Y+019250X0200Y         S2      
017TP_U8_P05        VIA   -           A10X+165400Y+019250X0260Y         S2      
017TP_U8_P05              -     D0100PA00X+165400Y+019250                       
317m0000            VIA   -    MD0100PA00X+164500Y+018450X0200Y         S0      
327m0000            U39   -8          A10X+164350Y+016316X0140Y0590R270 S2      
317m0000            VIA   -    MD0100PA00X+109450Y+036050X0200Y         S0      
317m0000            VIA   -    MD0100PA00X+102627Y+030373X0200Y         S0      
317m0000            VIA   -    MD0100PA00X+072292Y+029950X0200Y         S0      
327m0000            R5945 -2   M      A01X+072724Y+030060X0198Y0197R180 S1      
327m0000            U45   -4          A01X+072044Y+030526X0170Y0240R180 S1      
327m0000            VIA   -    M      A01X+071800Y+030000X0300Y         S1      
327m0001            VIA   -    M      A10X+163500Y+016450X0260Y         S2      
327m0001            U39   -7          A10X+164350Y+016060X0140Y0590R270 S2      
317m0001            VIA   -    MD0100PA00X+164200Y+018450X0200Y         S0      
317m0001            VIA   -    MD0100PA00X+065892Y+032000X0200Y         S0      
327m0001            U44   -4          A01X+064906Y+032474X0170Y0240     S1      
327m0001            R5944 -2   M      A01X+065892Y+032250X0198Y0197R180 S1      
317m0002            VIA   -    MD0100PA00X+162900Y+017500X0200Y         S0      
327m0002            U39   -6          A10X+164350Y+015804X0140Y0590R270 S2      
317m0002            VIA   -    M      A01X+117950Y+035500X0300Y         S1      
017m0002            VIA   -    M      A10X+117950Y+035500X0200Y         S1      
017m0002                  -    MD0100PA00X+117950Y+035500                       
327m0002            U43   -4          A10X+117606Y+036126X0170Y0240R180 S2      
327m0002            R5943 -2   M      A10X+117600Y+035658X0198Y0197R270 S2      
327m0003            VIA   -    M      A10X+116850Y+034442X0260Y         S2      
317m0003            VIA   -    MD0100PA00X+165800Y+017950X0200Y         S0      
327m0003            U39   -5          A10X+164350Y+015548X0140Y0590R270 S2      
317m0003            VIA   -    MD0100PA00X+117950Y+035000X0200Y         S0      
327m0003            U42   -4          A10X+115774Y+034306X0170Y0240R270 S2      
327m0003            R5942 -2   M      A10X+116300Y+034442X0198Y0197R090 S2      
327m0004            R5917 -1          A01X+165327Y+013052X0198Y0197R270 S1      
317m0004            VIA   -    M      A01X+168500Y+013300X0200Y         S2      
017m0004            VIA   -    M      A10X+168500Y+013300X0260Y         S2      
017m0004                  -    MD0100PA00X+168500Y+013300                       
327m0004            U40   -4          A10X+175882Y+019124X0220Y0320R270 S2      
327m0005            VIA   -    M      A10X+174350Y+018750X0260Y         S2      
327m0005            U40   -2          A10X+174938Y+018750X0220Y0320R270 S2      
327m0005            R5941 -2          A10X+173908Y+018650X0198Y0197R180 S2      
327m0006            VIA   -    M      A10X+174350Y+018100X0260Y         S2      
327m0006            U40   -1          A10X+174938Y+018376X0220Y0320R270 S2      
327m0006            R5940 -2          A10X+173908Y+018100X0198Y0197R180 S2      
327PU_U39_PIN1      R5931 -2          A10X+165242Y+013800X0198Y0197     S2      
327PU_U39_PIN1      VIA   -    M      A10X+164750Y+014000X0260Y         S2      
327PU_U39_PIN1      U39   -1          A10X+164350Y+014525X0140Y0590R270 S2      
327TP_U39_P17       VIA   -           A10X+168200Y+016000X0260Y         S2      
327TP_U39_P17       U39   -20         A10X+166650Y+015548X0140Y0590R270 S2      
327TP_U39_P16       VIA   -           A10X+166100Y+017850X0260Y         S2      
327TP_U39_P16       U39   -19         A10X+166650Y+015804X0140Y0590R270 S2      
327TP_U39_P15       VIA   -           A10X+168050Y+016500X0260Y         S2      
327TP_U39_P15       U39   -18         A10X+166650Y+016060X0140Y0590R270 S2      
327TP_U39_P14       VIA   -           A10X+167700Y+016950X0260Y         S2      
327TP_U39_P14       U39   -17         A10X+166650Y+016316X0140Y0590R270 S2      
327TP_U39_P13       VIA   -           A10X+166650Y+017850X0260Y         S2      
327TP_U39_P13       U39   -16         A10X+166650Y+016572X0140Y0590R270 S2      
327TP_U39_P12       VIA   -           A10X+168000Y+017500X0260Y         S2      
327TP_U39_P12       U39   -15         A10X+166650Y+016828X0140Y0590R270 S2      
327TP_U39_P11       VIA   -           A10X+167450Y+017500X0260Y         S2      
327TP_U39_P11       U39   -14         A10X+166650Y+017084X0140Y0590R270 S2      
327TP_U39_P10       VIA   -           A10X+167750Y+018200X0260Y         S2      
327TP_U39_P10       U39   -13         A10X+166650Y+017340X0140Y0590R270 S2      
327TP_U39_P07       VIA   -           A10X+165250Y+018500X0260Y         S2      
327TP_U39_P07       U39   -11         A10X+164350Y+017084X0140Y0590R270 S2      
327TP_U39_P06       VIA   -           A10X+165850Y+018300X0260Y         S2      
327TP_U39_P06       U39   -10         A10X+164350Y+016828X0140Y0590R270 S2      
327TP_U39_P05       VIA   -           A10X+164150Y+017800X0260Y         S2      
327TP_U39_P05       U39   -9          A10X+164350Y+016572X0140Y0590R270 S2      
327m0007            R5933 -2          A10X+167792Y+014550X0198Y0197     S2      
327m0007            VIA   -    M      A10X+167300Y+014650X0260Y         S2      
327m0007            U39   -22         A10X+166650Y+015037X0140Y0590R270 S2      
327m0008            R5932 -2          A10X+167792Y+014150X0198Y0197     S2      
327m0008            VIA   -    M      A10X+167300Y+014100X0260Y         S2      
327m0008            U39   -23         A10X+166650Y+014781X0140Y0590R270 S2      
327PCA9555_2_A2     R5937 -1          A10X+163008Y+014950X0198Y0197     S2      
327PCA9555_2_A2     VIA   -    M      A10X+163450Y+014750X0260Y         S2      
327PCA9555_2_A2     U39   -3          A10X+164350Y+015037X0140Y0590R270 S2      
327PCA9555_2_A2     R5934 -2   M      A10X+163008Y+014600X0198Y0197R180 S2      
327PCA9555_2_A1     VIA   -    M      A10X+163500Y+014250X0260Y         S2      
327PCA9555_2_A1     U39   -2          A10X+164350Y+014781X0140Y0590R270 S2      
327PCA9555_2_A1     R5935 -2   M      A10X+163008Y+014250X0198Y0197R180 S2      
327PCA9555_2_A1     R5938 -1          A10X+163008Y+013900X0198Y0197     S2      
327PCA9555_2_A0     R5936 -2          A10X+167792Y+015350X0198Y0197     S2      
327PCA9555_2_A0     R5939 -1   M      A10X+167792Y+014950X0198Y0197R180 S2      
327PCA9555_2_A0     VIA   -    M      A10X+167325Y+015175X0260Y         S2      
327PCA9555_2_A0     U39   -21         A10X+166650Y+015292X0140Y0590R270 S2      
327m0009            R5916 -2          A01X+162784Y+011514X0198Y0197     S1      
327m0009            U38   -10         A01X+163445Y+011517X0100Y0320R270 S1      
317m0009            VIA   -    M      A01X+163132Y+011514X0200Y         S2      
017m0009            VIA   -    M      A10X+163132Y+011514X0260Y         S2      
017m0009                  -    MD0100PA00X+163132Y+011514                       
317m0009            VIA   -    MD0100PA00X+162692Y+015600X0200Y         S0      
327m0009            R5930 -1          A10X+162692Y+015350X0198Y0197R180 S2      
327m0010            R5915 -1          A01X+177800Y+019558X0198Y0197R270 S1      
327m0010            VIA   -    M      A01X+177800Y+020050X0300Y         S1      
327m0010            U37   -D          A01X+177244Y+019100X0320Y0360R270 S1      
327m0010            R5914 -2   M      A01X+177258Y+020050X0198Y0197     S1      
317m0011            VIA   -    M      A01X+181150Y+018600X0200Y         S2      
017m0011            VIA   -    M      A10X+181150Y+018600X0260Y         S2      
017m0011                  -    MD0100PA00X+181150Y+018600                       
317m0011            VIA   -    MD0100PA00X+177800Y+018950X0200Y         S0      
327m0011            R5915 -2          A01X+177800Y+019242X0198Y0197R270 S1      
317m0011            J11   -S2   D0410PA00X+185396Y+031921X0610Y    R090 S3      
327m0012            R5928 -1          A01X+163158Y+016350X0198Y0197R180 S1      
327m0012            VIA   -    M      A01X+163650Y+016250X0300Y         S1      
327m0012            U8    -7          A01X+164350Y+016572X0140Y0590R270 S1      
327m0013            R5927 -1          A01X+163158Y+016750X0198Y0197R180 S1      
327m0013            VIA   -    M      A01X+163650Y+016800X0300Y         S1      
327m0013            U8    -6          A01X+164350Y+016828X0140Y0590R270 S1      
327m0014            R5924 -2          A10X+164108Y+013058X0198Y0197R270 S2      
327m0014            C101  -1          A10X+164528Y+013055X0198Y0197R090 S2      
327m0014            VIA   -    M      A10X+164322Y+013505X0260Y         S2      
327m0015            VIA   -    M      A10X+163008Y+015800X0260Y         S2      
327m0015            R5930 -2          A10X+163008Y+015350X0198Y0197R180 S2      
327m0015            U39   -4          A10X+164350Y+015292X0140Y0590R270 S2      
327m0016            U37   -G          A01X+176456Y+019474X0320Y0360R270 S1      
327m0016            VIA   -    M      A01X+176300Y+020050X0300Y         S1      
327m0016            U36   -D          A01X+175844Y+019100X0320Y0360R270 S1      
327m0016            R5913 -2   M      A01X+175808Y+020050X0198Y0197     S1      
327LED_D6_R1        R5929 -2          A01X+172892Y+025000X0198Y0197R180 S1      
327LED_D6_R1        VIA   -    M      A01X+172492Y+024550X0300Y         S1      
327LED_D6_R1        D6    -A          A01X+173100Y+024537X0240Y0280R270 S1      
327m0017            U8    -14         A01X+166650Y+015548X0140Y0590R270 S1      
327m0017            R5880 -2          A10X+069018Y+031276X0440Y0540R270 S2      
327m0017            U33   -2          A01X+172482Y+019850X0220Y0320R090 S1      
317m0017            VIA   -    MD0100PA00X+069176Y+030900X0200Y    R180 S0      
317m0017            VIA   -    M      A01X+088510Y+036150X0200Y         S2      
017m0017            VIA   -    M      A10X+088510Y+036150X0260Y         S2      
017m0017                  -    MD0100PA00X+088510Y+036150                       
317m0017            VIA   -    MD0100PA00X+086710Y+003150X0200Y         S0      
317m0017            VIA   -    MD0100PA00X+170710Y+014250X0200Y         S0      
317m0017            VIA   -    MD0100PA00X+172160Y+019850X0200Y         S0      
327m0017            R5881 -1   M      A10X+069176Y+030650X0198Y0197     S2      
327m0017            PU9   -17         A10X+069376Y+029158X0120Y0330R180 S2      
327m0017            PR7029-1   M      A10X+069311Y+030200X0198Y0197R180 S2      
327m0017            R423  -2          A01X+163518Y+014200X0198Y0197     S1      
317m0017            VIA   -    M      A01X+166760Y+019850X0300Y         S1      
017m0017            VIA   -    M      A10X+166760Y+019850X0200Y         S1      
017m0017                  -    MD0100PA00X+166760Y+019850                       
327m0018            U8    -13         A01X+166650Y+015292X0140Y0590R270 S1      
327m0018            R148  -2          A10X+107210Y+023924X0440Y0540R090 S2      
327m0018            U33   -1          A01X+172482Y+019476X0220Y0320R090 S1      
327m0018            VIA   -    M      A10X+088266Y+035084X0260Y         S2      
317m0018            VIA   -    MD0100PA00X+107052Y+024300X0200Y         S0      
317m0018            VIA   -    MD0100PA00X+088750Y+035568X0200Y         S0      
317m0018            VIA   -    MD0100PA00X+086710Y+002800X0200Y         S0      
317m0018            VIA   -    MD0100PA00X+170510Y+014050X0200Y         S0      
317m0018            VIA   -    MD0100PA00X+172160Y+019476X0200Y         S0      
327m0018            PU7   -17         A10X+106852Y+026042X0120Y0330     S2      
327m0018            R149  -1   M      A10X+107052Y+024550X0198Y0197R180 S2      
327m0018            PR6935-1   M      A10X+106918Y+025000X0198Y0197     S2      
317m0018            VIA   -    MD0100PA00X+166150Y+019900X0200Y         S0      
327m0018            R419  -2          A01X+165558Y+019900X0198Y0197     S1      
317m0019            VIA   -    MD0100PA00X+169550Y+007650X0200Y         S0      
317m0019            J8    -S5   D0295PA00X+148020Y+002301X0455Y    R270 S3      
317m0019            VIA   -    MD0100PA00X+170100Y+016450X0200Y         S0      
327m0019            VIA   -    M      A01X+162150Y+016500X0300Y         S1      
327m0019            R5911 -2          A01X+161558Y+016950X0198Y0197     S1      
317m0019            VIA   -    MD0100PA00X+162600Y+016750X0200Y         S0      
327m0019            R5927 -2          A01X+162842Y+016750X0198Y0197R180 S1      
317m0020            VIA   -    MD0100PA00X+170100Y+015900X0200Y         S0      
327m0020            VIA   -    M      A01X+162150Y+015900X0300Y         S1      
327m0020            R5912 -2          A01X+161558Y+016550X0198Y0197     S1      
317m0020            VIA   -    MD0100PA00X+162600Y+016350X0200Y         S0      
327m0020            R5928 -2          A01X+162842Y+016350X0198Y0197R180 S1      
317m0020            VIA   -    MD0100PA00X+169200Y+007657X0200Y         S0      
317m0020            J9    -S5   D0295PA00X+028965Y+002301X0455Y    R270 S3      
327P12V_LED_FB      R5919 -2   M      A01X+162494Y+011123X0180Y0200R270 S1      
327P12V_LED_FB      R5921 -2          A01X+162096Y+011123X0180Y0200R270 S1      
327P12V_LED_FB      R5925 -2   M      A01X+162896Y+011123X0198Y0197R090 S1      
327P12V_LED_FB      U38   -11         A01X+163445Y+011123X0100Y0320R270 S1      
317P12V_LED_FB      VIA   -    M      A01X+163234Y+010912X0200Y         S2      
017P12V_LED_FB      VIA   -    M      A10X+163234Y+010912X0260Y         S2      
017P12V_LED_FB            -    MD0100PA00X+163234Y+010912                       
327P12V_LED_PD      VIA   -           A01X+163053Y+009056X0300Y         S1      
327P12V_LED_PD      R5918 -2   M      A01X+163520Y+009094X0180Y0200     S1      
327P12V_LED_PD      U38   -12         A01X+163603Y+010769X0100Y0320R180 S1      
327P12V_LED_PD      R5920 -2          A01X+163476Y+009593X0280Y0320R270 S1      
327P12V_LED_PD      C98   -2          A01X+163476Y+010103X0280Y0320R270 S1      
327P12V_LED_IMON    R5926 -1   M      A01X+162777Y+012736X0198Y0197R090 S1      
327P12V_LED_IMON    C100  -1   M      A01X+163177Y+012736X0198Y0197R090 S1      
327P12V_LED_IMON    U38   -8          A01X+163799Y+011871X0100Y0320R180 S1      
327P12V_LED_IMON    VIA   -           A01X+162239Y+012736X0300Y         S1      
327P12V_LED_FLTB    U38   -9          A01X+163603Y+011871X0100Y0320R180 S1      
327P12V_LED_FLTB    VIA   -           A01X+161818Y+012047X0300Y         S1      
327P12V_LED_FLTB    R5922 -1   M      A01X+162784Y+011914X0198Y0197R180 S1      
327P12V_LED_SS      C99   -1          A01X+163877Y+012736X0198Y0197R090 S1      
327P12V_LED_SS      U38   -6          A01X+164193Y+011871X0100Y0320R180 S1      
317P12V_LED_SS      VIA   -    M      A01X+164193Y+012297X0200Y         S2      
017P12V_LED_SS      VIA   -    M      A10X+164193Y+012297X0260Y         S2      
017P12V_LED_SS            -    MD0100PA00X+164193Y+012297                       
327P12V_LED_ISET    R5923 -1          A01X+164528Y+012742X0198Y0197R090 S1      
327P12V_LED_ISET    R5924 -1          A10X+164108Y+012743X0198Y0197R270 S2      
327P12V_LED_ISET    U38   -5          A01X+164390Y+011871X0100Y0320R180 S1      
317P12V_LED_ISET    VIA   -    MD0100PA00X+164492Y+012458X0200Y         S0      
327P12V_LED_ISET    VIA   -    M      A10X+163640Y+012743X0260Y         S2      
327P12V_LED_TIMER   C97   -1          A01X+164927Y+012736X0198Y0197R090 S1      
327P12V_LED_TIMER   U38   -4          A01X+164587Y+011871X0100Y0320R180 S1      
317P12V_LED_TIMER   VIA   -    M      A01X+165132Y+012508X0200Y         S2      
017P12V_LED_TIMER   VIA   -    M      A10X+165132Y+012508X0260Y         S2      
017P12V_LED_TIMER         -    MD0100PA00X+165132Y+012508                       
327P12V_LED_EN_R    R5917 -2   M      A01X+165327Y+012736X0198Y0197R270 S1      
327P12V_LED_EN_R    U38   -1          A01X+165177Y+011861X0098Y0335R180 S1      
317P12V_LED_EN_R    VIA   -           A01X+165666Y+012736X0200Y         S2      
017P12V_LED_EN_R    VIA   -           A10X+165666Y+012736X0260Y         S2      
017P12V_LED_EN_R          -     D0100PA00X+165666Y+012736                       
317m0021            VIA   -    MD0100PA00X+115350Y+034250X0200Y         S0      
327m0021            U42   -2          A10X+115026Y+034050X0170Y0240R270 S2      
317m0021            VIA   -    MD0100PA00X+109450Y+035560X0200Y         S0      
327m0021            R5902 -2          A10X+108174Y+036050X0440Y0540     S2      
327m0021            VIA   -    M      A10X+110120Y+035560X0260Y    R180 S2      
327m0021            C90   -1   M      A10X+110700Y+035560X0280Y0320     S2      
327m0021            R5904 -1   M      A10X+111250Y+035892X0198Y0197R270 S2      
327m0021            U34   -1          A10X+111878Y+035876X0220Y0320R270 S2      
327P3V3_AND         R5901 -2          A10X+111300Y+035324X0440Y0540R090 S2      
327P3V3_AND         VIA   -    M      A10X+113300Y+035324X0260Y         S2      
327P3V3_AND         C91   -1   M      A10X+113900Y+036092X0198Y0197R270 S2      
327P3V3_AND         R5903 -1   M      A10X+113500Y+036092X0198Y0197R270 S2      
327P3V3_AND         U34   -5          A10X+112822Y+035876X0220Y0320R270 S2      
327FM_HS1_EN_FUSE   U34   -2          A10X+111878Y+036250X0220Y0320R270 S2      
317FM_HS1_EN_FUSE   VIA   -    M      A01X+112340Y+035630X0300Y         S1      
017FM_HS1_EN_FUSE   VIA   -    M      A10X+112340Y+035630X0200Y         S1      
017FM_HS1_EN_FUSE         -    MD0100PA00X+112340Y+035630                       
327FM_HS1_EN_FUSE   U43   -2          A10X+117350Y+036874X0170Y0240R180 S2      
317FM_HS1_EN_FUSE   VIA   -    MD0100PA00X+117890Y+035962X0200Y         S0      
317FM_HS1_EN_FUSE   VIA   -    MD0100PA00X+102452Y+021500X0200Y         S0      
327FM_HS1_EN_FUSE   R398  -2          A10X+102460Y+019724X0440Y0540R090 S2      
327FM_HS1_EN_FUSE   R413  -2   M      A10X+102452Y+021250X0198Y0197     S2      
327FM_HS1_EN_FUSE   C69   -1   M      A10X+102320Y+020350X0280Y0320R270 S2      
327FM_HS1_EN_FUSE   R399  -1   M      A10X+102452Y+020850X0198Y0197R180 S2      
317FM_HS2_EN_FUSE   VIA   -    MD0100PA00X+071200Y+021550X0200Y         S0      
327FM_HS2_EN_FUSE   R5893 -2          A10X+070860Y+019674X0440Y0540R090 S2      
327FM_HS2_EN_FUSE   R5896 -2   M      A10X+071058Y+021200X0198Y0197R180 S2      
327FM_HS2_EN_FUSE   R5897 -1   M      A10X+071058Y+020800X0198Y0197     S2      
327FM_HS2_EN_FUSE   C88   -1   M      A10X+071000Y+020300X0280Y0320R090 S2      
327FM_HS2_EN_FUSE   U45   -2   M      A01X+072300Y+031274X0170Y0240R180 S1      
327FM_HS2_EN_FUSE   U35   -2          A01X+067428Y+031950X0220Y0320R270 S1      
327FM_HS2_EN_FUSE   VIA   -    M      A01X+071404Y+032689X0300Y         S1      
327m0022            VIA   -    M      A01X+064950Y+030850X0300Y    R180 S1      
327m0022            R5908 -1   M      A01X+066350Y+031758X0198Y0197R270 S1      
327m0022            U35   -1          A01X+067428Y+032324X0220Y0320R270 S1      
327m0022            C92   -1   M      A01X+066800Y+032090X0280Y0320R180 S1      
327m0022            R5906 -2   M      A01X+063100Y+031376X0440Y0540R090 S1      
327m0022            U44   -2          A01X+064650Y+031726X0170Y0240     S1      
327P3V3_2_AND       VIA   -    M      A01X+067100Y+033192X0300Y         S1      
327P3V3_2_AND       R5907 -1   M      A01X+067650Y+033192X0198Y0197R090 S1      
327P3V3_2_AND       C93   -1   M      A01X+068050Y+033192X0198Y0197R090 S1      
327P3V3_2_AND       U35   -5          A01X+068372Y+032324X0220Y0320R270 S1      
327P3V3_2_AND       R5905 -2          A01X+059824Y+031800X0440Y0540R180 S1      
317TP_H35           H35   -1    D1670PA00X+094020Y+008848X3150Y         S3      
317TP_H34           H34   -1    D1670PA00X+094020Y+031348X3150Y         S3      
317TP_H33           H33   -1    D1670PA00X+082209Y+008848X3150Y         S3      
317TP_H32           H32   -1    D1670PA00X+082209Y+031348X3150Y         S3      
327P52V_2_FUSE_1    R384  -1          A01X+070424Y+017800X0440Y0540     S1      
317P52V_2_FUSE_1    VIA   -    MD0100PA00X+070424Y+018500X0200Y         S0      
327P52V_2_FUSE_1    R5893 -1   M      A10X+070860Y+018926X0440Y0540R090 S2      
317P52V_2_FUSE_1    VIA   -    MD0100PA00X+074660Y+018500X0200Y         S0      
317P52V_2_FUSE_1    VIA   -    MD0100PA00X+074960Y+018800X0200Y         S0      
317P52V_2_FUSE_1    VIA   -    MD0100PA00X+075260Y+018800X0200Y         S0      
317P52V_2_FUSE_1    VIA   -    MD0100PA00X+075560Y+018800X0200Y         S0      
317P52V_2_FUSE_1    VIA   -    MD0100PA00X+075860Y+018800X0200Y         S0      
317P52V_2_FUSE_1    VIA   -    MD0100PA00X+074660Y+018800X0200Y         S0      
317P52V_2_FUSE_1    VIA   -    M      A01X+075860Y+018500X0200Y         S2      
017P52V_2_FUSE_1    VIA   -    M      A10X+075860Y+018500X0260Y         S2      
017P52V_2_FUSE_1          -    MD0100PA00X+075860Y+018500                       
317P52V_2_FUSE_1    VIA   -    MD0100PA00X+075560Y+018500X0200Y         S0      
317P52V_2_FUSE_1    VIA   -    MD0100PA00X+075260Y+018500X0200Y         S0      
317P52V_2_FUSE_1    VIA   -    MD0100PA00X+074960Y+018500X0200Y         S0      
317P52V_2_FUSE_1    VIA   -    MD0100PA00X+072010Y+018800X0200Y         S0      
317P52V_2_FUSE_1    VIA   -    MD0100PA00X+072310Y+018800X0200Y         S0      
317P52V_2_FUSE_1    VIA   -    MD0100PA00X+073210Y+018800X0200Y         S0      
317P52V_2_FUSE_1    VIA   -    MD0100PA00X+072910Y+018800X0200Y         S0      
317P52V_2_FUSE_1    VIA   -    MD0100PA00X+072610Y+018800X0200Y         S0      
317P52V_2_FUSE_1    VIA   -    MD0100PA00X+072310Y+018500X0200Y         S0      
317P52V_2_FUSE_1    VIA   -    M      A01X+072010Y+018500X0200Y         S2      
017P52V_2_FUSE_1    VIA   -    M      A10X+072010Y+018500X0260Y         S2      
017P52V_2_FUSE_1          -    MD0100PA00X+072010Y+018500                       
317P52V_2_FUSE_1    VIA   -    M      A01X+072610Y+018500X0300Y         S1      
017P52V_2_FUSE_1    VIA   -    M      A10X+072610Y+018500X0200Y         S1      
017P52V_2_FUSE_1          -    MD0100PA00X+072610Y+018500                       
317P52V_2_FUSE_1    VIA   -    MD0100PA00X+072910Y+018500X0200Y         S0      
317P52V_2_FUSE_1    VIA   -    MD0100PA00X+073210Y+018500X0200Y         S0      
327P52V_2_FUSE_1    PD11  -C          A10X+075260Y+019501X0950Y1300R270 S2      
327P52V_2_FUSE_1    PD12  -C          A10X+072610Y+019501X0950Y1300R270 S2      
327P52V_2_FUSE_1    FS6   -1          A10X+073960Y+017691X1280Y1350R090 S2      
327m0023            VIA   -    M      A10X+108994Y+027126X0260Y         S2      
327m0023            PU7   -9          A10X+107915Y+026908X0120Y0330R090 S2      
327m0023            R81   -2          A10X+109452Y+027150X0198Y0197     S2      
327m0023            R146  -2   M      A10X+109452Y+026750X0198Y0197     S2      
327m0024            VIA   -    M      A10X+067220Y+028370X0260Y         S2      
327m0024            PU9   -9          A10X+068313Y+028292X0120Y0330R270 S2      
327m0024            R5886 -2          A10X+066776Y+028050X0198Y0197R180 S2      
327m0024            R5884 -2   M      A10X+066776Y+028450X0198Y0197R180 S2      
327m0025            PC614 -2          A01X+064110Y+025150X0280Y0320R090 S1      
327m0025            PR6997-2          A01X+051501Y+032900X0180Y0200R180 S1      
317m0025            VIA   -    M      A01X+051741Y+032900X0200Y         S2      
017m0025            VIA   -    M      A10X+051741Y+032900X0260Y         S2      
017m0025                  -    MD0100PA00X+051741Y+032900                       
317m0025            VIA   -    MD0100PA00X+061850Y+033350X0200Y    R090 S0      
327m0025            R5881 -2          A10X+068861Y+030650X0198Y0197     S2      
327m0025            PR7025-2          A10X+070076Y+030650X0198Y0197R180 S2      
327m0025            PC616 -2          A10X+070618Y+030500X0400Y0500R180 S2      
327m0025            PR7034-2          A10X+066452Y+030050X0198Y0197     S2      
327m0025            PR7011-2          A10X+064468Y+030850X0198Y0197R180 S2      
327m0025            PC602 -2          A10X+064608Y+030350X0280Y0320R270 S2      
327m0025            PC600 -1          A10X+060511Y+030250X0198Y0197R180 S2      
327m0025            R5876 -2          A10X+061668Y+031408X0198Y0197R270 S2      
327m0025            R5875 -2          A10X+061268Y+031408X0198Y0197R270 S2      
327m0025            PC595 -2          A10X+060648Y+031250X0460Y0620     S2      
327m0025            PU9   -19         A10X+069770Y+029158X0120Y0330R180 S2      
327m0025            PC611 -2          A10X+066528Y+027400X0280Y0320R090 S2      
327m0025            PC603 -2          A10X+064276Y+029350X0198Y0197R180 S2      
327m0025            PC604 -2          A10X+064276Y+029800X0198Y0197R180 S2      
327m0025            PR7007-2          A10X+063826Y+028450X0198Y0197R180 S2      
327m0025            PR7013-1          A10X+063826Y+028850X0198Y0197     S2      
327m0025            PR7012-1          A10X+063826Y+027350X0198Y0197     S2      
327m0025            PR7015-2          A10X+064226Y+027750X0198Y0197R180 S2      
327m0025            PU8   -14         A10X+060964Y+028939X0110Y0300R180 S2      
327m0025            PC607 -2          A10X+069580Y+024200X0460Y0620R180 S2      
317m0025            VIA   -    MD0100PA00X+069843Y+024712X0200Y    R180 S0      
327m0025            PC613 -2   M      A10X+069968Y+024942X0198Y0197R090 S2      
327m0025            PC606 -2          A10X+068418Y+024942X0198Y0197R090 S2      
327m0025            PR7021-2          A10X+068818Y+024942X0198Y0197R090 S2      
327m0025            PC612 -2          A10X+067218Y+024942X0198Y0197R090 S2      
327m0025            PC577 -2          A10X+067610Y+024942X0198Y0197R090 S2      
327m0025            PR6979-2          A10X+068010Y+024942X0198Y0197R090 S2      
327m0025            PC578 -2          A01X+069518Y+025150X0198Y0197     S1      
327m0025            PR6980-2          A01X+069518Y+025550X0198Y0197     S1      
327m0025            PU9   -PAD1M      A10X+069121Y+027800X1100Y2200R180 S2      
317m0025            VIA   -    MD0100PA00X+069558Y+026810X0200Y    R180 S0      
317m0025            VIA   -    MD0100PA00X+069568Y+028790X0200Y    R180 S0      
317m0025            VIA   -    MD0100PA00X+068678Y+028790X0200Y    R180 S0      
317m0025            VIA   -    MD0100PA00X+069558Y+027800X0200Y    R180 S0      
317m0025            VIA   -    MD0100PA00X+068678Y+027800X0200Y    R180 S0      
317m0025            VIA   -    MD0100PA00X+068678Y+026810X0200Y    R180 S0      
327m0025            PC615 -2   M      A01X+064950Y+026058X0198Y0197R090 S1      
327m0025            R5895 -2          A01X+065411Y+026600X0198Y0197R180 S1      
317m0025            VIA   -    MD0100PA00X+065110Y+026600X0200Y    R180 S0      
327m0025            PR7036-2          A01X+065411Y+025600X0198Y0197R180 S1      
327m0025            R5894 -2   M      A01X+065411Y+026050X0198Y0197R180 S1      
327m0025            PC610 -2          A10X+066311Y+025850X0198Y0197     S2      
327m0025            PR7028-2          A10X+066111Y+026700X0198Y0197     S2      
327m0025            PR7030-2          A10X+066311Y+025450X0198Y0197     S2      
327m0025            PR7035-2          A01X+065411Y+025150X0198Y0197R180 S1      
317m0025            VIA   -    MD0100PA00X+065010Y+025150X0200Y    R180 S0      
327m0025            PU8   -33         A10X+061357Y+026261X0110Y0300R180 S2      
327m0025            PU8   -34         A10X+061160Y+026261X0110Y0300R180 S2      
327m0025            PC601 -2          A10X+060768Y+024942X0198Y0197R090 S2      
327m0025            PR7010-2          A10X+060776Y+024550X0198Y0197R180 S2      
327m0025            PJ5   -1          A10X+060768Y+023995X0280Y0740     S2      
327m0025            PU8   -40  M      A10X+061013Y+027600X1437Y2126R180 S2      
317m0025            VIA   -    MD0100PA00X+060468Y+026700X0200Y    R180 S0      
317m0025            VIA   -    MD0100PA00X+061618Y+028500X0200Y    R180 S0      
317m0025            VIA   -    MD0100PA00X+060468Y+028500X0200Y    R180 S0      
317m0025            VIA   -    MD0100PA00X+060468Y+027600X0200Y    R180 S0      
317m0025            VIA   -    MD0100PA00X+061618Y+027600X0200Y    R180 S0      
317m0025            VIA   -    MD0100PA00X+061618Y+026700X0200Y    R180 S0      
317P3V3_HPDB_PG_R   VIA   -    M      A01X+174792Y+020400X0200Y         S2      
017P3V3_HPDB_PG_R   VIA   -    M      A10X+174792Y+020400X0260Y         S2      
017P3V3_HPDB_PG_R         -    MD0100PA00X+174792Y+020400                       
327P3V3_HPDB_PG_R   R5900 -1          A01X+174792Y+020050X0198Y0197     S1      
317P3V3_HPDB_PG_R   VIA   -    MD0100PA00X+176760Y+035000X0200Y         S0      
327P3V3_HPDB_PG_R   PU5   -9          A01X+176273Y+034235X0120Y0320R270 S1      
327P3V3_HPDB_PG_R   PR110 -2          A01X+177182Y+035630X0198Y0197R180 S1      
327m0026            R424  -1          A01X+162210Y+015208X0198Y0197R270 S1      
317m0026            VIA   -    M      A01X+162210Y+015593X0200Y         S2      
017m0026            VIA   -    M      A10X+162210Y+015593X0260Y         S2      
017m0026                  -    MD0100PA00X+162210Y+015593                       
317m0026            VIA   -    MD0100PA00X+060570Y+025950X0200Y         S0      
327m0026            PU8   -37         A10X+060570Y+026261X0110Y0300R180 S2      
327m0027            VIA   -    M      A01X+171000Y+020350X0300Y         S1      
327m0027            U33   -4          A01X+171538Y+020224X0220Y0320R090 S1      
327m0027            R5898 -1   M      A01X+170750Y+019858X0198Y0197R270 S1      
327m0027            R5899 -2          A01X+170608Y+020800X0198Y0197     S1      
317m0028            VIA   -    MD0100PA00X+056301Y+011412X0200Y         S0      
327m0028            PR6989-1B         A01X+056606Y+011630X0100Y0200R180 S1      
317m0028            VIA   -    M      A01X+057423Y+013240X0200Y         S2      
017m0028            VIA   -    M      A10X+057423Y+013240X0260Y         S2      
017m0028                  -    MD0100PA00X+057423Y+013240                       
327m0028            PR6987-1   M      A01X+057423Y+013530X0280Y0320R090 S1      
327m0028            PR6992-2          A01X+057423Y+014930X0280Y0320R270 S1      
327m0028            PR6991-2   M      A01X+057423Y+014230X0280Y0320R270 S1      
327m0029            PR6997-1          A01X+051186Y+032900X0180Y0200R180 S1      
327m0029            PR6996-2   M      A01X+051186Y+032900X0180Y0200R180 S1      
327m0029            VIA   -           A01X+048530Y+033210X0300Y         S1      
327m0029            PQ44  -E   M      A01X+049918Y+032950X0400Y0500R090 S1      
317m0030            VIA   -    M      A01X+055143Y+013240X0200Y         S2      
017m0030            VIA   -    M      A10X+055143Y+013240X0260Y         S2      
017m0030                  -    MD0100PA00X+055143Y+013240                       
327m0030            PR6988-1   M      A01X+055143Y+013530X0280Y0320R270 S1      
327m0030            PR6993-2          A01X+055143Y+014930X0280Y0320R090 S1      
327m0030            PR6990-2   M      A01X+055143Y+014230X0280Y0320R090 S1      
317m0030            VIA   -    MD0100PA00X+056301Y+011848X0200Y         S0      
327m0030            PR6989-2B         A01X+055995Y+011630X0100Y0200R180 S1      
327m0031            VIA   -           A01X+053400Y+027500X0300Y         S1      
327m0031            VIA   -           A01X+053700Y+022700X0300Y         S1      
327m0031            VIA   -           A01X+054600Y+021500X0300Y         S1      
327m0031            VIA   -           A01X+054700Y+019500X0300Y         S1      
317m0031            VIA   -    MD0100PA00X+052508Y+021110X0200Y    R180 S0      
317m0031            VIA   -    MD0100PA00X+052208Y+021110X0200Y    R180 S0      
317m0031            VIA   -    MD0100PA00X+052508Y+020510X0200Y    R180 S0      
317m0031            VIA   -    MD0100PA00X+052508Y+020810X0200Y    R180 S0      
317m0031            VIA   -    MD0100PA00X+052508Y+020210X0200Y         S0      
317m0031            VIA   -    MD0100PA00X+052508Y+019910X0200Y         S0      
317m0031            VIA   -    MD0100PA00X+052208Y+020210X0200Y         S0      
317m0031            VIA   -    MD0100PA00X+052208Y+020810X0200Y    R180 S0      
317m0031            VIA   -    MD0100PA00X+052208Y+020510X0200Y    R180 S0      
317m0031            VIA   -    MD0100PA00X+052208Y+019910X0200Y         S0      
317m0031            VIA   -    MD0100PA00X+052808Y+025550X0200Y    R180 S0      
317m0031            VIA   -    MD0100PA00X+052808Y+024950X0200Y    R180 S0      
317m0031            VIA   -    MD0100PA00X+052808Y+025250X0200Y    R180 S0      
317m0031            VIA   -    MD0100PA00X+052808Y+024650X0200Y         S0      
317m0031            VIA   -    MD0100PA00X+052808Y+024350X0200Y         S0      
317m0031            VIA   -    MD0100PA00X+052508Y+025550X0200Y    R180 S0      
317m0031            VIA   -    MD0100PA00X+052208Y+025550X0200Y    R180 S0      
317m0031            VIA   -    MD0100PA00X+052508Y+024950X0200Y    R180 S0      
317m0031            VIA   -    MD0100PA00X+052508Y+025250X0200Y    R180 S0      
317m0031            VIA   -    MD0100PA00X+052508Y+024650X0200Y         S0      
317m0031            VIA   -    MD0100PA00X+052508Y+024350X0200Y         S0      
317m0031            VIA   -    MD0100PA00X+052208Y+024650X0200Y         S0      
317m0031            VIA   -    MD0100PA00X+052208Y+025250X0200Y    R180 S0      
317m0031            VIA   -    MD0100PA00X+052208Y+024950X0200Y    R180 S0      
317m0031            VIA   -    MD0100PA00X+052208Y+024350X0200Y         S0      
317m0031            VIA   -    MD0100PA00X+052208Y+028790X0200Y         S0      
317m0031            VIA   -    MD0100PA00X+052208Y+029090X0200Y         S0      
317m0031            VIA   -    MD0100PA00X+052508Y+029090X0200Y         S0      
317m0031            VIA   -    MD0100PA00X+052508Y+028790X0200Y         S0      
317m0031            VIA   -    MD0100PA00X+052808Y+028790X0200Y         S0      
317m0031            VIA   -    MD0100PA00X+053108Y+028790X0200Y         S0      
317m0031            VIA   -    MD0100PA00X+052808Y+029090X0200Y         S0      
317m0031            VIA   -    MD0100PA00X+053108Y+029090X0200Y         S0      
317m0031            VIA   -    MD0100PA00X+052208Y+029390X0200Y    R180 S0      
317m0031            VIA   -    MD0100PA00X+052508Y+029390X0200Y    R180 S0      
317m0031            VIA   -    MD0100PA00X+052808Y+029390X0200Y    R180 S0      
317m0031            VIA   -    MD0100PA00X+053108Y+029390X0200Y    R180 S0      
317m0031            VIA   -    MD0100PA00X+052208Y+029690X0200Y    R180 S0      
317m0031            VIA   -    MD0100PA00X+052508Y+029690X0200Y    R180 S0      
317m0031            VIA   -    MD0100PA00X+052808Y+029690X0200Y    R180 S0      
317m0031            VIA   -    MD0100PA00X+053108Y+029690X0200Y    R180 S0      
317m0031            VIA   -    MD0100PA00X+052208Y+029990X0200Y    R180 S0      
317m0031            VIA   -    MD0100PA00X+052508Y+029990X0200Y    R180 S0      
317m0031            VIA   -    MD0100PA00X+052808Y+029990X0200Y    R180 S0      
317m0031            VIA   -    MD0100PA00X+053108Y+029990X0200Y    R180 S0      
327m0031            PQ38  -D          A01X+049856Y+029390X3327Y4173     S1      
327m0031            PR6976-2A         A01X+055415Y+024950X1260Y2700     S1      
327m0031            PQ39  -D          A01X+049856Y+024950X3327Y4173     S1      
327m0031            PQ40  -D          A01X+049856Y+020510X3327Y4173     S1      
327m0032            VIA   -           A01X+053300Y+015600X0300Y         S1      
327m0032            VIA   -           A01X+053600Y+005700X0300Y         S1      
327m0032            VIA   -           A01X+054300Y+017200X0300Y         S1      
327m0032            VIA   -           A01X+054700Y+008700X0300Y         S1      
327m0032            VIA   -           A01X+054800Y+006800X0300Y         S1      
327m0032            PQ41  -D          A01X+049856Y+016070X3327Y4173     S1      
327m0032            PR6989-2A         A01X+055415Y+011630X1260Y2700     S1      
327m0032            PQ42  -D          A01X+049856Y+011630X3327Y4173     S1      
327m0032            PQ43  -D          A01X+049856Y+007190X3327Y4173     S1      
317m0032            VIA   -    MD0100PA00X+052208Y+015470X0200Y         S0      
317m0032            VIA   -    MD0100PA00X+052208Y+016070X0200Y    R180 S0      
317m0032            VIA   -    MD0100PA00X+052208Y+016370X0200Y    R180 S0      
317m0032            VIA   -    MD0100PA00X+052208Y+015770X0200Y         S0      
317m0032            VIA   -    MD0100PA00X+052508Y+015470X0200Y         S0      
317m0032            VIA   -    MD0100PA00X+052508Y+015770X0200Y         S0      
317m0032            VIA   -    MD0100PA00X+052508Y+016370X0200Y    R180 S0      
317m0032            VIA   -    MD0100PA00X+052508Y+016070X0200Y    R180 S0      
317m0032            VIA   -    MD0100PA00X+052208Y+016670X0200Y    R180 S0      
317m0032            VIA   -    MD0100PA00X+052508Y+016670X0200Y    R180 S0      
317m0032            VIA   -    MD0100PA00X+052808Y+011030X0200Y         S0      
317m0032            VIA   -    MD0100PA00X+052808Y+011330X0200Y         S0      
317m0032            VIA   -    MD0100PA00X+052808Y+011930X0200Y    R180 S0      
317m0032            VIA   -    MD0100PA00X+052808Y+011630X0200Y    R180 S0      
317m0032            VIA   -    MD0100PA00X+052808Y+012230X0200Y    R180 S0      
317m0032            VIA   -    MD0100PA00X+052208Y+011030X0200Y         S0      
317m0032            VIA   -    MD0100PA00X+052208Y+011630X0200Y    R180 S0      
317m0032            VIA   -    MD0100PA00X+052208Y+011930X0200Y    R180 S0      
317m0032            VIA   -    MD0100PA00X+052208Y+011330X0200Y         S0      
317m0032            VIA   -    MD0100PA00X+052508Y+011030X0200Y         S0      
317m0032            VIA   -    MD0100PA00X+052508Y+011330X0200Y         S0      
317m0032            VIA   -    MD0100PA00X+052508Y+011930X0200Y    R180 S0      
317m0032            VIA   -    MD0100PA00X+052508Y+011630X0200Y    R180 S0      
317m0032            VIA   -    MD0100PA00X+052208Y+012230X0200Y    R180 S0      
317m0032            VIA   -    MD0100PA00X+052508Y+012230X0200Y    R180 S0      
317m0032            VIA   -    MD0100PA00X+052208Y+006590X0200Y         S0      
317m0032            VIA   -    MD0100PA00X+052208Y+006890X0200Y         S0      
317m0032            VIA   -    MD0100PA00X+052208Y+007190X0200Y    R180 S0      
317m0032            VIA   -    MD0100PA00X+052208Y+007490X0200Y    R180 S0      
317m0032            VIA   -    MD0100PA00X+052208Y+007790X0200Y    R180 S0      
317m0032            VIA   -    MD0100PA00X+052508Y+006590X0200Y         S0      
317m0032            VIA   -    MD0100PA00X+052508Y+006890X0200Y         S0      
317m0032            VIA   -    MD0100PA00X+052508Y+007190X0200Y    R180 S0      
317m0032            VIA   -    MD0100PA00X+052508Y+007490X0200Y    R180 S0      
317m0032            VIA   -    MD0100PA00X+052508Y+007790X0200Y    R180 S0      
317m0032            VIA   -    MD0100PA00X+052808Y+006590X0200Y         S0      
317m0032            VIA   -    MD0100PA00X+052808Y+006890X0200Y         S0      
317m0032            VIA   -    MD0100PA00X+052808Y+007190X0200Y    R180 S0      
317m0032            VIA   -    MD0100PA00X+052808Y+007490X0200Y    R180 S0      
317m0032            VIA   -    MD0100PA00X+053108Y+006590X0200Y         S0      
317m0032            VIA   -    MD0100PA00X+053108Y+006890X0200Y         S0      
317m0032            VIA   -    MD0100PA00X+053108Y+007190X0200Y    R180 S0      
317m0032            VIA   -    MD0100PA00X+053108Y+007490X0200Y    R180 S0      
317m0032            VIA   -    MD0100PA00X+052808Y+007790X0200Y    R180 S0      
317m0032            VIA   -    MD0100PA00X+053108Y+007790X0200Y    R180 S0      
327m0033            PU1   -11         A10X+115855Y+026261X0110Y0300     S2      
317m0033            VIA   -    MD0100PA00X+107334Y+029224X0200Y         S0      
327m0033            PU7   -46         A10X+107246Y+028758X0120Y0330     S2      
327m0033            PC576 -1   M      A01X+106968Y+031150X0198Y0197R180 S1      
327m0033            PR483 -1   M      A01X+106968Y+030750X0198Y0197R180 S1      
317m0033            VIA   -    MD0100PA00X+106460Y+032400X0200Y         S0      
327m0033            PR481 -2          A10X+106460Y+032776X0440Y0540R270 S2      
317m0033            VIA   -    M      A01X+116327Y+025531X0300Y         S1      
017m0033            VIA   -    M      A10X+116327Y+025531X0200Y         S1      
017m0033                  -    MD0100PA00X+116327Y+025531                       
327m0034            PU9   -10         A10X+068313Y+028489X0120Y0330R270 S2      
327m0034            VIA   -    M      A10X+067380Y+028940X0260Y    R180 S2      
327m0034            R5882 -2          A10X+066776Y+029250X0198Y0197R180 S2      
327P52V_HS2_VCC     VIA   -           A10X+070798Y+025238X0260Y         S2      
327P52V_HS2_VCC     PC607 -1          A10X+070740Y+024200X0460Y0620R180 S2      
327P52V_HS2_VCC     PR7020-2          A10X+070660Y+023480X0400Y0630R270 S2      
317P52V_HS2_VCC     VIA   -    MD0100PA00X+070668Y+027240X0200Y    R180 S0      
317P52V_HS2_VCC     VIA   -    MD0100PA00X+070298Y+027240X0200Y    R180 S0      
317P52V_HS2_VCC     VIA   -    MD0100PA00X+070668Y+028350X0200Y    R180 S0      
317P52V_HS2_VCC     VIA   -    MD0100PA00X+070298Y+028350X0200Y    R180 S0      
327P52V_HS2_VCC     PU9   -41         A10X+070360Y+026442X0120Y0330R180 S2      
327P52V_HS2_VCC     PU9   -22         A10X+070754Y+029158X0120Y0330R180 S2      
327P52V_HS2_VCC     PU9   -21         A10X+070557Y+029158X0120Y0330R180 S2      
327P52V_HS2_VCC     PU9   -20         A10X+070360Y+029158X0120Y0330R180 S2      
327P52V_HS2_VCC     PU9   -PAD2M      A10X+070479Y+027800X0590Y1340R180 S2      
327P52V_HS2_VCC     PU9   -24         A10X+071148Y+029158X0120Y0330R180 S2      
327P52V_HS2_VCC     PU9   -23         A10X+070951Y+029158X0120Y0330R180 S2      
327P52V_HS2_TEMPP   PR6995-1          A01X+050871Y+032200X0180Y0200R180 S1      
317P52V_HS2_TEMPP   VIA   -    M      A01X+050631Y+032200X0200Y         S2      
017P52V_HS2_TEMPP   VIA   -    M      A10X+050631Y+032200X0260Y         S2      
017P52V_HS2_TEMPP         -    MD0100PA00X+050631Y+032200                       
327P52V_HS2_TEMPP   PU9   -44         A10X+069376Y+026442X0120Y0330R180 S2      
317P52V_HS2_TEMPP   VIA   -    MD0100PA00X+069211Y+024802X0200Y    R180 S0      
327P52V_HS2_TEMPP   PC609 -1   M      A10X+069211Y+025100X0198Y0197R180 S2      
317P52V_HS2_UVH     VIA   -    M      A01X+068168Y+023082X0200Y    R180 S2      
017P52V_HS2_UVH     VIA   -    M      A10X+068168Y+023082X0260Y    R180 S2      
017P52V_HS2_UVH           -    MD0100PA00X+068168Y+023082                       
327P52V_HS2_UVH     PR7019-2          A10X+068168Y+022424X0440Y0540R090 S2      
327P52V_HS2_UVH     PU9   -45         A10X+069179Y+026442X0120Y0330R180 S2      
317P52V_HS2_UVH     VIA   -    MD0100PA00X+069179Y+026107X0200Y    R180 S0      
327P52V_HS2_UVH     PC606 -1          A10X+068418Y+025258X0198Y0197R090 S2      
327P52V_HS2_UVH     PR7021-1   M      A10X+068818Y+025258X0198Y0197R090 S2      
327m0035            PC614 -1          A01X+064690Y+025150X0280Y0320R090 S1      
327m0035            VIA   -    M      A01X+065050Y+024660X0300Y         S1      
327m0035            PR7031-2          A01X+066361Y+025150X0198Y0197R180 S1      
327m0035            PR7035-1   M      A01X+065726Y+025150X0198Y0197R180 S1      
327P52V_HS2_VCP     VIA   -           A10X+072121Y+028467X0260Y         S2      
327P52V_HS2_VCP     PU9   -29         A10X+071423Y+028095X0120Y0330R270 S2      
327P52V_HS2_VCP     PC608 -2          A10X+072918Y+028580X0460Y0620R090 S2      
327P52V_HS2_GPO1    VIA   -    M      A10X+068785Y+029900X0260Y         S2      
327P52V_HS2_GPO1    PU9   -14         A10X+068785Y+029158X0120Y0330R180 S2      
327P52V_HS2_GPO1    R5890 -1   M      A10X+066768Y+030450X0198Y0197     S2      
327P52V_HS2_GPO1    R5889 -2          A10X+066768Y+030850X0198Y0197R180 S2      
327m0036            R145  -2          A10X+109452Y+025550X0198Y0197     S2      
327m0036            VIA   -    M      A10X+108710Y+026050X0260Y         S2      
327m0036            PU7   -11         A10X+107915Y+026514X0120Y0330R090 S2      
327m0037            VIA   -    M      A01X+067140Y+026100X0300Y         S1      
327m0037            PU9   -5          A10X+068313Y+027505X0120Y0330R270 S2      
317m0037            VIA   -    MD0100PA00X+067618Y+027400X0200Y    R180 S0      
327m0037            PR7032-1          A01X+066676Y+025600X0198Y0197R180 S1      
327m0038            PU9   -11         A10X+068313Y+028686X0120Y0330R270 S2      
327m0038            VIA   -    M      A10X+067224Y+029444X0260Y    R180 S2      
327m0038            R5883 -2          A10X+066776Y+029650X0198Y0197R180 S2      
327P52V_HS2_GPO2    R5887 -2          A01X+068068Y+030250X0198Y0197     S1      
317P52V_HS2_GPO2    VIA   -    M      A01X+068588Y+029700X0300Y         S1      
017P52V_HS2_GPO2    VIA   -    M      A10X+068588Y+029700X0200Y         S1      
017P52V_HS2_GPO2          -    MD0100PA00X+068588Y+029700                       
327P52V_HS2_GPO2    PU9   -13         A10X+068588Y+029158X0120Y0330R180 S2      
327P52V_HS2_GPO2    R5888 -1   M      A01X+068068Y+029850X0198Y0197R180 S1      
327P52V_HS2_VREG    PU9   -42         A10X+069770Y+026442X0120Y0330R180 S2      
327P52V_HS2_VREG    VIA   -    M      A10X+069850Y+025773X0260Y    R180 S2      
327P52V_HS2_VREG    PC613 -1          A10X+069968Y+025258X0198Y0197R090 S2      
327m0039            PR7028-1          A10X+066426Y+026700X0198Y0197     S2      
327m0039            PU9   -2          A10X+068313Y+026914X0120Y0330R270 S2      
327m0039            VIA   -    M      A10X+067718Y+026700X0260Y    R180 S2      
327m0039            PR7027-1   M      A10X+066861Y+026900X0198Y0197R180 S2      
327P52V_HS2_ISET    VIA   -           A10X+066600Y+024100X0260Y         S2      
327P52V_HS2_ISET    PR7023-2          A10X+066568Y+022424X0440Y0540R090 S2      
327P52V_HS2_ISET    PR7024-2          A10X+066492Y+023350X0440Y0540     S2      
327P52V_HS2_ISET    PR7026-1          A10X+066626Y+026250X0198Y0197     S2      
327P52V_HS2_ISET    PR7030-1          A10X+066626Y+025450X0198Y0197     S2      
327P52V_HS2_ISET    PC610 -1          A10X+066626Y+025850X0198Y0197     S2      
327P52V_HS2_ISET    PU9   -1          A10X+068313Y+026717X0120Y0330R270 S2      
327m0040            R144  -2          A10X+109452Y+025950X0198Y0197     S2      
327m0040            VIA   -    M      A10X+108685Y+026575X0260Y         S2      
327m0040            PU7   -10         A10X+107915Y+026711X0120Y0330R090 S2      
327m0041            PU9   -4          A10X+068313Y+027308X0120Y0330R270 S2      
317m0041            VIA   -    M      A01X+067918Y+027319X0300Y    R180 S1      
017m0041            VIA   -    M      A10X+067918Y+027319X0200Y    R180 S1      
017m0041                  -    MD0100PA00X+067918Y+027319                       
327m0041            PR7031-1          A01X+066676Y+025150X0198Y0197R180 S1      
327P52V_HS2_MCB     PR7034-1          A10X+066768Y+030050X0198Y0197     S2      
327P52V_HS2_MCB     PU9   -12         A10X+068313Y+028883X0120Y0330R270 S2      
327P52V_HS2_MCB     VIA   -    M      A10X+068010Y+029760X0260Y    R180 S2      
317m0042            VIA   -    MD0100PA00X+064920Y+025450X0200Y         S2      
327m0042            PR7032-2          A01X+066361Y+025600X0198Y0197R180 S1      
327m0042            PR7036-1   M      A01X+065726Y+025600X0198Y0197R180 S1      
327m0042            PC615 -1          A01X+064950Y+025742X0198Y0197R090 S1      
327P52V_HS1_VCC     PR5   -2          A10X+103660Y+030070X0400Y0630R090 S2      
327P52V_HS1_VCC     VIA   -           A10X+104534Y+029877X0260Y         S2      
327P52V_HS1_VCC     PC587 -1          A10X+105510Y+030120X0460Y0620R090 S2      
317P52V_HS1_VCC     VIA   -    MD0100PA00X+105930Y+027960X0200Y         S0      
317P52V_HS1_VCC     VIA   -    MD0100PA00X+105560Y+026850X0200Y         S0      
317P52V_HS1_VCC     VIA   -    MD0100PA00X+105930Y+026850X0200Y         S0      
317P52V_HS1_VCC     VIA   -    MD0100PA00X+105560Y+027960X0200Y         S0      
327P52V_HS1_VCC     PU7   -41         A10X+105868Y+028758X0120Y0330     S2      
327P52V_HS1_VCC     PU7   -PAD2M      A10X+105749Y+027400X0590Y1340     S2      
327P52V_HS1_VCC     PU7   -23         A10X+105277Y+026042X0120Y0330     S2      
327P52V_HS1_VCC     PU7   -22         A10X+105474Y+026042X0120Y0330     S2      
327P52V_HS1_VCC     PU7   -21         A10X+105671Y+026042X0120Y0330     S2      
327P52V_HS1_VCC     PU7   -20         A10X+105868Y+026042X0120Y0330     S2      
327P52V_HS1_VCC     PU7   -24         A10X+105080Y+026042X0120Y0330     S2      
317P52V_HS1_GPO1    VIA   -    M      A01X+107443Y+025646X0300Y         S1      
017P52V_HS1_GPO1    VIA   -    M      A10X+107443Y+025646X0200Y         S1      
017P52V_HS1_GPO1          -    MD0100PA00X+107443Y+025646                       
327P52V_HS1_GPO1    PU7   -14         A10X+107443Y+026042X0120Y0330     S2      
327P52V_HS1_GPO1    R357  -2          A01X+108252Y+025150X0198Y0197R180 S1      
327P52V_HS1_GPO1    R358  -1   M      A01X+108252Y+025550X0198Y0197     S1      
327P52V_HS1_MCB     PU7   -12         A10X+107915Y+026317X0120Y0330R090 S2      
327P52V_HS1_MCB     VIA   -    M      A10X+108285Y+025675X0260Y         S2      
327P52V_HS1_MCB     PR35  -1          A10X+109452Y+025150X0198Y0197R180 S2      
327P52V_HS1_RND     PC9   -1          A10X+109010Y+029942X0198Y0197R270 S2      
327P52V_HS1_RND     VIA   -    M      A10X+108553Y+029443X0260Y         S2      
327P52V_HS1_RND     PU7   -48         A10X+107640Y+028758X0120Y0330     S2      
327P52V_HS1_VREG    PC10  -1          A10X+106260Y+029942X0198Y0197R270 S2      
327P52V_HS1_VREG    VIA   -    M      A10X+106403Y+029496X0260Y         S2      
327P52V_HS1_VREG    PU7   -42         A10X+106458Y+028758X0120Y0330     S2      
327m0043            VIA   -    M      A01X+109020Y+028860X0300Y         S1      
327m0043            PR31  -1          A01X+109552Y+029600X0198Y0197     S1      
317m0043            VIA   -    MD0100PA00X+108610Y+027800X0200Y         S0      
327m0043            PU7   -5          A10X+107915Y+027695X0120Y0330R090 S2      
327P52V_HS1_VCP     VIA   -           A10X+104054Y+026683X0260Y         S2      
327P52V_HS1_VCP     PU7   -29         A10X+104805Y+027105X0120Y0330R090 S2      
327P52V_HS1_VCP     PC588 -2          A10X+103310Y+026620X0460Y0620R270 S2      
327m0044            PR7022-2          A10X+069918Y+031276X0440Y0540R270 S2      
327m0044            PU9   -18         A10X+069573Y+029158X0120Y0330R180 S2      
327m0044            VIA   -    M      A10X+069573Y+029695X0260Y    R180 S2      
327m0044            PR7029-2   M      A10X+069626Y+030200X0198Y0197R180 S2      
327m0044            PR7025-1   M      A10X+069761Y+030650X0198Y0197R180 S2      
327P52V_HS1_DV_DT   PC13  -1          A10X+104910Y+024700X0400Y0500     S2      
327P52V_HS1_DV_DT   VIA   -    M      A10X+104184Y+025376X0260Y         S2      
327P52V_HS1_DV_DT   PR32  -2          A10X+104184Y+024700X0440Y0540     S2      
327m0045            PC11  -1          A01X+111460Y+030050X0280Y0320R270 S1      
327m0045            VIA   -    M      A01X+111214Y+030540X0300Y         S1      
327m0045            PR93  -2          A01X+109868Y+030050X0198Y0197     S1      
327m0045            PR36  -1   M      A01X+110502Y+030050X0198Y0197     S1      
327P52V_HS2_DV_DT   PR7033-2          A10X+072044Y+030500X0440Y0540R180 S2      
327P52V_HS2_DV_DT   VIA   -    M      A10X+071318Y+029850X0260Y    R180 S2      
327P52V_HS2_DV_DT   PC616 -1          A10X+071318Y+030500X0400Y0500R180 S2      
327P52V_HS1_UVH     VIA   -    M      A10X+107229Y+029492X0260Y         S2      
317P52V_HS1_UVH     VIA   -    MD0100PA00X+107049Y+029093X0200Y         S0      
327P52V_HS1_UVH     PU7   -45         A10X+107049Y+028758X0120Y0330     S2      
327P52V_HS1_UVH     PC586 -1          A10X+107810Y+029942X0198Y0197R270 S2      
327P52V_HS1_UVH     PR6931-1   M      A10X+107410Y+029942X0198Y0197R270 S2      
317P52V_HS1_UVH     VIA   -    MD0100PA00X+107260Y+032400X0200Y         S0      
327P52V_HS1_UVH     PR4   -2          A10X+107260Y+032776X0440Y0540R270 S2      
327P52V_HS2_RND     PU9   -48         A10X+068588Y+026442X0120Y0330R180 S2      
327P52V_HS2_RND     VIA   -    M      A10X+067676Y+025757X0260Y    R180 S2      
327P52V_HS2_RND     PC612 -1          A10X+067218Y+025258X0198Y0197R090 S2      
327P52V_HS1_GPO2    VIA   -    M      A10X+107810Y+025350X0260Y         S2      
327P52V_HS1_GPO2    PU7   -13         A10X+107640Y+026042X0120Y0330     S2      
327P52V_HS1_GPO2    R150  -2          A10X+109452Y+024350X0198Y0197     S2      
327P52V_HS1_GPO2    R151  -1   M      A10X+109452Y+024750X0198Y0197R180 S2      
327m0046            PR7033-1          A10X+072792Y+030500X0440Y0540R180 S2      
317m0046            VIA   -    M      A01X+072500Y+029250X0200Y    R180 S2      
017m0046            VIA   -    M      A10X+072500Y+029250X0260Y    R180 S2      
017m0046                  -    MD0100PA00X+072500Y+029250                       
317m0046            VIA   -    MD0100PA00X+071948Y+027898X0200Y    R180 S0      
327m0046            PU9   -30         A10X+071423Y+027898X0120Y0330R270 S2      
327m0047            PR93  -1          A01X+109552Y+030050X0198Y0197     S1      
317m0047            VIA   -    M      A01X+108310Y+027881X0300Y         S1      
017m0047            VIA   -    M      A10X+108310Y+027881X0200Y         S1      
017m0047                  -    MD0100PA00X+108310Y+027881                       
327m0047            PU7   -4          A10X+107915Y+027892X0120Y0330R090 S2      
317m0048            VIA   -    MD0100PA00X+056283Y+014380X0200Y         S0      
327m0048            PR6990-1          A01X+055723Y+014230X0280Y0320R090 S1      
327m0048            PR6986-1          A01X+055723Y+026850X0280Y0320R090 S1      
317m0048            VIA   -    M      A01X+056283Y+026650X0200Y         S2      
017m0048            VIA   -    M      A10X+056283Y+026650X0260Y         S2      
017m0048                  -    MD0100PA00X+056283Y+026650                       
327m0048            PU9   -38         A10X+070951Y+026442X0120Y0330R180 S2      
317m0048            VIA   -    MD0100PA00X+071008Y+026110X0200Y    R180 S0      
327P52V_HS1_ISET    VIA   -           A10X+109050Y+029050X0260Y         S2      
327P52V_HS1_ISET    PR19  -2          A10X+109686Y+031200X0440Y0540R180 S2      
327P52V_HS1_ISET    PR18  -2          A10X+108810Y+032776X0440Y0540R270 S2      
327P52V_HS1_ISET    PR21  -1   M      A10X+109602Y+029750X0198Y0197R180 S2      
327P52V_HS1_ISET    PC590 -1          A10X+109602Y+029350X0198Y0197R180 S2      
327P52V_HS1_ISET    PR6933-1          A10X+109602Y+028950X0198Y0197R180 S2      
327P52V_HS1_ISET    PU7   -1          A10X+107915Y+028483X0120Y0330R090 S2      
317m0049            VIA   -    MD0100PA00X+111200Y+029600X0200Y         S2      
327m0049            PR37  -1   M      A01X+110818Y+029600X0198Y0197R180 S1      
327m0049            PC12  -1          A01X+111502Y+029600X0198Y0197     S1      
327m0049            PR31  -2          A01X+109868Y+029600X0198Y0197     S1      
317m0050            VIA   -    M      A01X+056283Y+014030X0200Y         S2      
017m0050            VIA   -    M      A10X+056283Y+014030X0260Y         S2      
017m0050                  -    MD0100PA00X+056283Y+014030                       
327m0050            PR6991-1          A01X+056843Y+014230X0280Y0320R270 S1      
317m0050            VIA   -    MD0100PA00X+056283Y+027000X0200Y         S0      
327m0050            PR6985-1          A01X+056843Y+026850X0280Y0320R270 S1      
327m0050            PU9   -39         A10X+070754Y+026442X0120Y0330R180 S2      
317m0050            VIA   -    MD0100PA00X+070698Y+026110X0200Y    R180 S0      
327m0051            PR20  -1          A10X+109802Y+028500X0198Y0197R180 S2      
327m0051            PR6934-1   M      A10X+109368Y+028300X0198Y0197     S2      
327m0051            VIA   -    M      A10X+108510Y+028500X0260Y         S2      
327m0051            PU7   -2          A10X+107915Y+028286X0120Y0330R090 S2      
327m0052            R5866 -2          A10X+043810Y+021742X0198Y0197R090 S2      
317m0052            VIA   -    MD0100PA00X+043810Y+021450X0200Y         S0      
327m0052            PU9   -32         A10X+071423Y+027505X0120Y0330R270 S2      
317m0052            VIA   -    M      A01X+071738Y+027340X0300Y    R180 S1      
017m0052            VIA   -    M      A10X+071738Y+027340X0200Y    R180 S1      
017m0052                  -    MD0100PA00X+071738Y+027340                       
317m0052            VIA   -    MD0100PA00X+043810Y+017000X0200Y         S0      
327m0052            R5867 -1          A10X+043810Y+017302X0198Y0197R270 S2      
317m0053            VIA   -    M      A01X+103436Y+025400X0200Y         S2      
017m0053            VIA   -    M      A10X+103436Y+025400X0260Y         S2      
017m0053                  -    MD0100PA00X+103436Y+025400                       
327m0053            PR32  -1          A10X+103436Y+024700X0440Y0540     S2      
317m0053            VIA   -    MD0100PA00X+104280Y+027302X0200Y         S0      
327m0053            PU7   -30         A10X+104805Y+027302X0120Y0330R090 S2      
327P52V_HS2_TEMPN   PR6996-1          A01X+050871Y+032900X0180Y0200R180 S1      
317P52V_HS2_TEMPN   VIA   -    M      A01X+050631Y+032900X0200Y         S2      
017P52V_HS2_TEMPN   VIA   -    M      A10X+050631Y+032900X0260Y         S2      
017P52V_HS2_TEMPN         -    MD0100PA00X+050631Y+032900                       
327P52V_HS2_TEMPN   PU9   -43         A10X+069573Y+026442X0120Y0330R180 S2      
317P52V_HS2_TEMPN   VIA   -    MD0100PA00X+069526Y+024802X0200Y    R180 S0      
327P52V_HS2_TEMPN   PC609 -2   M      A10X+069526Y+025100X0198Y0197R180 S2      
327m0054            PR17  -2          A10X+106310Y+023924X0440Y0540R090 S2      
327m0054            PR6932-1   M      A10X+106468Y+024550X0198Y0197     S2      
327m0054            PR6935-2   M      A10X+106602Y+025000X0198Y0197     S2      
327m0054            VIA   -    M      A10X+106655Y+025505X0260Y         S2      
327m0054            PU7   -18         A10X+106655Y+026042X0120Y0330     S2      
327m0055            PR7003-2          A10X+041750Y+017540X0280Y0320     S2      
327m0055            VIA   -    M      A10X+041200Y+017500X0260Y         S2      
327m0055            PC598 -1          A10X+041240Y+016950X0280Y0320R090 S2      
327m0056            PR7001-1          A10X+042200Y+017308X0180Y0200R270 S2      
327m0056            VIA   -           A10X+041730Y+018520X0260Y         S2      
327m0056            PD18  -2          A10X+042810Y+017890X0320Y0340R270 S2      
327m0056            PC593 -2   M      A10X+042100Y+018010X0280Y0320R270 S2      
327m0057            PR7039-1   M      A01X+056430Y+015530X0198Y0197R180 S1      
327m0057            PR6992-1          A01X+056843Y+014930X0280Y0320R270 S1      
317m0057            VIA   -    M      A01X+056430Y+016078X0300Y         S1      
017m0057            VIA   -    M      A10X+056430Y+016078X0200Y         S1      
017m0057                  -    MD0100PA00X+056430Y+016078                       
327m0057            PU8   -9          A10X+059320Y+028683X0110Y0280R270 S2      
327m0058            PU8   -3          A10X+059330Y+026911X0110Y0300R270 S2      
317m0058            VIA   -    MD0100PA00X+057044Y+030270X0200Y         S0      
327m0058            VIA   -    M      A10X+057781Y+027808X0260Y         S2      
327m0058            PR7000-2   M      A10X+042200Y+021442X0180Y0200R270 S2      
327m0058            PR7002-1          A10X+041750Y+021360X0280Y0320     S2      
317m0058            VIA   -    MD0100PA00X+043061Y+021139X0200Y         S0      
327m0058            R5865 -2   M      A10X+043410Y+021742X0198Y0197R090 S2      
327m0058            PC594 -1          A10X+041750Y+020890X0280Y0320R180 S2      
327m0058            PD17  -1   M      A10X+042810Y+021470X0320Y0340R090 S2      
327m0059            PR7041-1   M      A01X+056430Y+028750X0198Y0197R180 S1      
327m0059            PR6981-1          A01X+056843Y+028250X0280Y0320R270 S1      
317m0059            VIA   -    M      A01X+057154Y+028906X0200Y         S2      
017m0059            VIA   -    M      A10X+057154Y+028906X0260Y         S2      
017m0059                  -    MD0100PA00X+057154Y+028906                       
327m0059            PU8   -6          A10X+059330Y+028092X0110Y0300R270 S2      
327m0060            R5870 -2          A10X+063511Y+026900X0198Y0197     S2      
327m0060            VIA   -    M      A10X+063068Y+026900X0260Y    R180 S2      
327m0060            PU8   -27         A10X+062007Y+027108X0110Y0300R270 S2      
317m0061            VIA   -    M      A01X+068968Y+023076X0200Y    R180 S2      
017m0061            VIA   -    M      A10X+068968Y+023076X0260Y    R180 S2      
017m0061                  -    MD0100PA00X+068968Y+023076                       
327m0061            PR6978-2          A10X+068968Y+022424X0440Y0540R090 S2      
317m0061            VIA   -    MD0100PA00X+068894Y+025976X0200Y    R180 S0      
327m0061            PU9   -46         A10X+068982Y+026442X0120Y0330R180 S2      
327m0061            PR6980-1   M      A01X+069202Y+025550X0198Y0197     S1      
327m0061            PC578 -1   M      A01X+069202Y+025150X0198Y0197     S1      
317m0061            VIA   -    MD0100PA00X+060088Y+029594X0200Y    R180 S0      
327m0061            PU8   -11         A10X+060373Y+028939X0110Y0300R180 S2      
327m0062            PR6988-2          A01X+055723Y+013530X0280Y0320R270 S1      
317m0062            VIA   -    MD0100PA00X+056283Y+013680X0200Y         S0      
317m0062            VIA   -    MD0100PA00X+056283Y+027350X0200Y         S0      
327m0062            PR6984-1          A01X+055723Y+027550X0280Y0320R090 S1      
317m0062            VIA   -    M      A01X+059030Y+027698X0300Y    R180 S1      
017m0062            VIA   -    M      A10X+059030Y+027698X0200Y    R180 S1      
017m0062                  -    MD0100PA00X+059030Y+027698                       
327m0062            PU8   -4          A10X+059330Y+027698X0110Y0300R270 S2      
327m0063            PR6993-1          A01X+055723Y+014930X0280Y0320R090 S1      
327m0063            PR7039-2   M      A01X+056116Y+015530X0198Y0197R180 S1      
317m0063            VIA   -    MD0100PA00X+056116Y+016078X0200Y         S2      
327m0063            PU8   -8          A10X+059330Y+028486X0110Y0300R270 S2      
327m0064            PR7041-2   M      A01X+056116Y+028750X0198Y0197R180 S1      
327m0064            PR6982-1          A01X+055723Y+028250X0280Y0320R090 S1      
317m0064            VIA   -    M      A01X+057132Y+029276X0300Y         S1      
017m0064            VIA   -    M      A10X+057132Y+029276X0200Y         S1      
017m0064                  -    MD0100PA00X+057132Y+029276                       
327m0064            PU8   -5          A10X+059330Y+027895X0110Y0300R270 S2      
327m0065            PR7001-2   M      A10X+042200Y+016992X0180Y0200R270 S2      
327m0065            PR7003-1   M      A10X+041750Y+016960X0280Y0320     S2      
317m0065            VIA   -    MD0100PA00X+042828Y+016706X0200Y         S0      
327m0065            R5868 -2   M      A10X+043410Y+017302X0198Y0197R090 S2      
327m0065            PD18  -1   M      A10X+042810Y+017030X0320Y0340R090 S2      
327m0065            PC597 -1          A10X+041700Y+016490X0280Y0320R180 S2      
327m0065            PU8   -2          A10X+059330Y+026714X0110Y0300R270 S2      
317m0065            VIA   -    MD0100PA00X+056509Y+030259X0200Y         S0      
327m0065            VIA   -    M      A10X+058156Y+027200X0260Y         S2      
327m0066            PR6987-2          A01X+056843Y+013530X0280Y0320R090 S1      
317m0066            VIA   -    MD0100PA00X+056283Y+013330X0200Y         S0      
327m0066            PR6983-1          A01X+056843Y+027550X0280Y0320R270 S1      
317m0066            VIA   -    MD0100PA00X+056283Y+027700X0200Y         S0      
317m0066            VIA   -    M      A01X+059030Y+028289X0300Y    R180 S1      
017m0066            VIA   -    M      A10X+059030Y+028289X0200Y    R180 S1      
017m0066                  -    MD0100PA00X+059030Y+028289                       
327m0066            PU8   -7          A10X+059330Y+028289X0110Y0300R270 S2      
327P52V_HS2_GATE4   VIA   -           A01X+043650Y+017560X0300Y         S1      
327P52V_HS2_GATE4   PQ41  -G          A01X+046234Y+017070X0520Y1220R270 S1      
327P52V_HS2_GATE4   PR6973-2   M      A01X+044484Y+017070X0280Y0320R180 S1      
327P52V_HS2_GATE2   VIA   -           A01X+043880Y+025950X0300Y         S1      
327P52V_HS2_GATE2   PQ39  -G          A01X+046234Y+025950X0520Y1220R270 S1      
327P52V_HS2_GATE2   PR6971-2   M      A01X+044484Y+025950X0280Y0320R180 S1      
327P52V_HS2_GATE5   VIA   -           A01X+043950Y+012630X0300Y         S1      
327P52V_HS2_GATE5   PQ42  -G          A01X+046234Y+012630X0520Y1220R270 S1      
327P52V_HS2_GATE5   PR6974-2   M      A01X+044484Y+012630X0280Y0320R180 S1      
327P52V_HS2_GATE3   VIA   -           A01X+043720Y+021910X0300Y         S1      
327P52V_HS2_GATE3   PR6972-2   M      A01X+044484Y+021510X0280Y0320R180 S1      
327P52V_HS2_GATE3   PQ40  -G          A01X+046234Y+021510X0520Y1220R270 S1      
327m0067            PR6973-1          A01X+044484Y+017650X0280Y0320R180 S1      
317m0067            VIA   -    MD0100PA00X+044194Y+017650X0200Y         S0      
327m0067            R5868 -1          A10X+043410Y+017618X0198Y0197R090 S2      
327m0067            R5867 -2   M      A10X+043810Y+017618X0198Y0197R270 S2      
317m0067            VIA   -    M      A01X+044194Y+013210X0200Y         S2      
017m0067            VIA   -    M      A10X+044194Y+013210X0260Y         S2      
017m0067                  -    MD0100PA00X+044194Y+013210                       
327m0067            PR6974-1          A01X+044484Y+013210X0280Y0320R180 S1      
317m0067            VIA   -    MD0100PA00X+044194Y+008770X0200Y         S0      
327m0067            PR6975-1          A01X+044484Y+008770X0280Y0320R180 S1      
327m0068            PR6970-1          A01X+044484Y+030970X0280Y0320R180 S1      
317m0068            VIA   -    M      A01X+044194Y+030970X0200Y         S2      
017m0068            VIA   -    M      A10X+044194Y+030970X0260Y         S2      
017m0068                  -    MD0100PA00X+044194Y+030970                       
317m0068            VIA   -    MD0100PA00X+044194Y+026530X0200Y         S0      
327m0068            PR6971-1          A01X+044484Y+026530X0280Y0320R180 S1      
327m0068            PR6972-1          A01X+044484Y+022090X0280Y0320R180 S1      
317m0068            VIA   -    MD0100PA00X+044194Y+022090X0200Y         S0      
327m0068            R5865 -1          A10X+043410Y+022058X0198Y0197R090 S2      
327m0068            R5866 -1   M      A10X+043810Y+022058X0198Y0197R090 S2      
327P52V_HS2_GATE1   PQ38  -G          A01X+046234Y+030390X0520Y1220R270 S1      
327P52V_HS2_GATE1   VIA   -           A01X+043910Y+030390X0300Y         S1      
327P52V_HS2_GATE1   PR6970-2   M      A01X+044484Y+030390X0280Y0320R180 S1      
327P52V_HS2_GATE6   VIA   -           A01X+043940Y+008190X0300Y         S1      
327P52V_HS2_GATE6   PQ43  -G          A01X+046234Y+008190X0520Y1220R270 S1      
327P52V_HS2_GATE6   PR6975-2   M      A01X+044484Y+008190X0280Y0320R180 S1      
327m0069            VIA   -           A01X+122800Y+027400X0300Y         S1      
327m0069            VIA   -           A01X+122600Y+025100X0300Y         S1      
327m0069            VIA   -           A01X+122700Y+022300X0300Y         S1      
327m0069            VIA   -           A01X+121200Y+021500X0300Y         S1      
327m0069            VIA   -           A01X+122300Y+019700X0300Y         S1      
317m0069            VIA   -    MD0100PA00X+123120Y+029990X0200Y    R180 S0      
317m0069            VIA   -    MD0100PA00X+123120Y+029690X0200Y    R180 S0      
317m0069            VIA   -    MD0100PA00X+123120Y+028790X0200Y         S0      
317m0069            VIA   -    MD0100PA00X+123120Y+029090X0200Y         S0      
317m0069            VIA   -    MD0100PA00X+123120Y+029390X0200Y         S0      
317m0069            VIA   -    MD0100PA00X+124020Y+021110X0200Y    R180 S0      
317m0069            VIA   -    MD0100PA00X+124020Y+020510X0200Y         S0      
317m0069            VIA   -    MD0100PA00X+124020Y+020210X0200Y         S0      
317m0069            VIA   -    MD0100PA00X+124020Y+019910X0200Y         S0      
317m0069            VIA   -    MD0100PA00X+124020Y+020810X0200Y    R180 S0      
317m0069            VIA   -    MD0100PA00X+123720Y+021110X0200Y    R180 S0      
317m0069            VIA   -    MD0100PA00X+123720Y+020810X0200Y    R180 S0      
317m0069            VIA   -    MD0100PA00X+123720Y+019910X0200Y         S0      
317m0069            VIA   -    MD0100PA00X+123720Y+020210X0200Y         S0      
317m0069            VIA   -    MD0100PA00X+123720Y+020510X0200Y         S0      
317m0069            VIA   -    MD0100PA00X+124020Y+025550X0200Y    R180 S0      
317m0069            VIA   -    MD0100PA00X+124020Y+024950X0200Y         S0      
317m0069            VIA   -    MD0100PA00X+124020Y+024650X0200Y         S0      
317m0069            VIA   -    MD0100PA00X+124020Y+024350X0200Y         S0      
317m0069            VIA   -    MD0100PA00X+124020Y+025250X0200Y    R180 S0      
317m0069            VIA   -    MD0100PA00X+123720Y+025550X0200Y    R180 S0      
317m0069            VIA   -    MD0100PA00X+123420Y+025550X0200Y    R180 S0      
317m0069            VIA   -    MD0100PA00X+123720Y+025250X0200Y    R180 S0      
317m0069            VIA   -    MD0100PA00X+123720Y+024350X0200Y         S0      
317m0069            VIA   -    MD0100PA00X+123720Y+024650X0200Y         S0      
317m0069            VIA   -    MD0100PA00X+123720Y+024950X0200Y         S0      
317m0069            VIA   -    MD0100PA00X+123420Y+025250X0200Y    R180 S0      
317m0069            VIA   -    MD0100PA00X+123420Y+024350X0200Y         S0      
317m0069            VIA   -    MD0100PA00X+123420Y+024650X0200Y         S0      
317m0069            VIA   -    MD0100PA00X+123420Y+024950X0200Y         S0      
317m0069            VIA   -    MD0100PA00X+123420Y+029990X0200Y    R180 S0      
317m0069            VIA   -    MD0100PA00X+123420Y+029390X0200Y         S0      
317m0069            VIA   -    MD0100PA00X+123420Y+029090X0200Y         S0      
317m0069            VIA   -    MD0100PA00X+123420Y+028790X0200Y         S0      
317m0069            VIA   -    MD0100PA00X+123420Y+029690X0200Y    R180 S0      
317m0069            VIA   -    MD0100PA00X+123720Y+029990X0200Y    R180 S0      
317m0069            VIA   -    MD0100PA00X+123720Y+029390X0200Y         S0      
317m0069            VIA   -    MD0100PA00X+123720Y+029090X0200Y         S0      
317m0069            VIA   -    MD0100PA00X+123720Y+028790X0200Y         S0      
317m0069            VIA   -    MD0100PA00X+123720Y+029690X0200Y    R180 S0      
317m0069            VIA   -    MD0100PA00X+124020Y+029690X0200Y    R180 S0      
317m0069            VIA   -    MD0100PA00X+124020Y+029990X0200Y    R180 S0      
317m0069            VIA   -    MD0100PA00X+124020Y+028790X0200Y         S0      
317m0069            VIA   -    MD0100PA00X+124020Y+029090X0200Y         S0      
317m0069            VIA   -    MD0100PA00X+124020Y+029390X0200Y         S0      
327m0069            PR479 -2A         A01X+120814Y+024950X1260Y2700R180 S1      
327m0069            PQ32  -D          A01X+126372Y+029390X3327Y4173R180 S1      
327m0069            PQ33  -D          A01X+126372Y+024950X3327Y4173R180 S1      
327m0069            PQ34  -D          A01X+126372Y+020510X3327Y4173R180 S1      
327P52V_HS1_GATE3   VIA   -           A01X+132400Y+019900X0300Y         S1      
327P52V_HS1_GATE3   PR476 -2   M      A01X+131745Y+019530X0280Y0320R180 S1      
327P52V_HS1_GATE3   PQ34  -G          A01X+129995Y+019510X0520Y1220R090 S1      
327m0070            PU1   -9          A10X+116909Y+026517X0110Y0280R090 S2      
327m0070            PR5864-1   M      A01X+119742Y+015530X0198Y0197     S1      
327m0070            PR6955-1          A01X+119350Y+014930X0280Y0320R090 S1      
317m0070            VIA   -    MD0100PA00X+119742Y+016028X0200Y         S2      
327m0071            VIA   -    M      A10X+118081Y+029794X0260Y         S2      
327m0071            PR6998-2   M      A10X+134010Y+015012X0180Y0200R270 S2      
327m0071            PR6999-1   M      A10X+134480Y+014980X0280Y0320     S2      
327m0071            PC581 -1          A10X+134500Y+014490X0280Y0320R180 S2      
327m0071            R5863 -2   M      A10X+132810Y+015342X0198Y0197R090 S2      
327m0071            PD16  -1   M      A10X+133410Y+015020X0320Y0340R090 S2      
317m0071            VIA   -    MD0100PA00X+133414Y+014664X0200Y         S0      
317m0071            VIA   -    MD0100PA00X+119713Y+031426X0200Y         S0      
327m0071            PU1   -2          A10X+116899Y+028486X0110Y0300R090 S2      
317m0072            VIA   -    MD0100PA00X+132035Y+015670X0200Y         S0      
327m0072            PR16  -1          A01X+131745Y+015670X0280Y0320R180 S1      
327m0072            R5863 -1          A10X+132810Y+015658X0198Y0197R090 S2      
327m0072            R5861 -2   M      A10X+132410Y+015658X0198Y0197R270 S2      
317m0072            VIA   -    M      A01X+132035Y+011230X0200Y         S2      
017m0072            VIA   -    M      A10X+132035Y+011230X0260Y         S2      
017m0072                  -    MD0100PA00X+132035Y+011230                       
327m0072            PR477 -1          A01X+131745Y+011230X0280Y0320R180 S1      
317m0072            VIA   -    MD0100PA00X+132035Y+006790X0200Y         S0      
327m0072            PR478 -1          A01X+131745Y+006790X0280Y0320R180 S1      
317m0073            VIA   -    MD0100PA00X+119910Y+013680X0200Y         S0      
327m0073            PR6961-1          A01X+119350Y+013530X0280Y0320R090 S1      
327m0073            PR6960-1          A01X+119350Y+027550X0280Y0320R090 S1      
317m0073            VIA   -    M      A01X+119910Y+027350X0300Y         S1      
017m0073            VIA   -    M      A10X+119910Y+027350X0200Y         S1      
017m0073                  -    MD0100PA00X+119910Y+027350                       
317m0073            VIA   -    MD0100PA00X+105530Y+029090X0200Y         S0      
327m0073            PU7   -39         A10X+105474Y+028758X0120Y0330     S2      
327m0074            PU1   -7          A10X+116899Y+026911X0110Y0300R090 S2      
327m0074            PR6964-2          A01X+119350Y+014230X0280Y0320R270 S1      
317m0074            VIA   -    MD0100PA00X+119910Y+014380X0200Y         S0      
317m0074            VIA   -    M      A01X+117199Y+026911X0300Y         S1      
017m0074            VIA   -    M      A10X+117199Y+026911X0200Y         S1      
017m0074                  -    MD0100PA00X+117199Y+026911                       
317m0074            VIA   -    MD0100PA00X+119910Y+026650X0200Y         S0      
327m0074            PR6963-1          A01X+119350Y+026850X0280Y0320R090 S1      
327m0075            PR6959-1          A01X+120470Y+013530X0280Y0320R270 S1      
317m0075            VIA   -    MD0100PA00X+119910Y+013330X0200Y         S2      
327m0075            PR6958-1          A01X+120470Y+027550X0280Y0320R270 S1      
317m0075            VIA   -    MD0100PA00X+119910Y+027700X0200Y         S0      
317m0075            VIA   -    MD0100PA00X+105220Y+029090X0200Y         S0      
327m0075            PU7   -38         A10X+105277Y+028758X0120Y0330     S2      
327m0076            PR6969-1   M      A01X+125042Y+033000X0180Y0200     S1      
327m0076            PR6968-2          A01X+125042Y+033000X0180Y0200     S1      
327m0076            VIA   -           A01X+127820Y+032950X0300Y         S1      
327m0076            PQ37  -E   M      A01X+126310Y+032950X0400Y0500R270 S1      
327m0077            PU1   -4          A10X+116899Y+027502X0110Y0300R090 S2      
327m0077            PR6965-2          A01X+120470Y+014230X0280Y0320R090 S1      
317m0077            VIA   -    MD0100PA00X+119910Y+014030X0200Y         S0      
317m0077            VIA   -    M      A01X+117199Y+027502X0300Y         S1      
017m0077            VIA   -    M      A10X+117199Y+027502X0200Y         S1      
017m0077                  -    MD0100PA00X+117199Y+027502                       
317m0077            VIA   -    MD0100PA00X+119910Y+027000X0200Y         S0      
327m0077            PR6962-1          A01X+120470Y+026850X0280Y0320R270 S1      
327P52V_HS1_GATE2   VIA   -           A01X+132370Y+023970X0300Y         S1      
327P52V_HS1_GATE2   PR475 -2   M      A01X+131745Y+023970X0280Y0320R180 S1      
327P52V_HS1_GATE2   PQ33  -G          A01X+129995Y+023950X0520Y1220R090 S1      
327P52V_HS1_GATE4   VIA   -           A01X+132350Y+010650X0300Y         S1      
327P52V_HS1_GATE4   PR477 -2   M      A01X+131745Y+010650X0280Y0320R180 S1      
327P52V_HS1_GATE4   PQ35  -G          A01X+129995Y+010630X0520Y1220R090 S1      
327P52V_HS1_TEMPN   PR6968-1          A01X+125358Y+033000X0180Y0200     S1      
317P52V_HS1_TEMPN   VIA   -    M      A01X+125598Y+033000X0200Y         S2      
017P52V_HS1_TEMPN   VIA   -    M      A10X+125598Y+033000X0260Y         S2      
017P52V_HS1_TEMPN         -    MD0100PA00X+125598Y+033000                       
317P52V_HS1_TEMPN   VIA   -    MD0100PA00X+106702Y+030398X0200Y         S0      
327P52V_HS1_TEMPN   PC589 -2   M      A10X+106702Y+030100X0198Y0197     S2      
327P52V_HS1_TEMPN   PU7   -43         A10X+106655Y+028758X0120Y0330     S2      
327m0078            VIA   -           A01X+121400Y+017700X0300Y         S1      
327m0078            VIA   -           A01X+122500Y+016500X0300Y         S1      
327m0078            VIA   -           A01X+122300Y+009600X0300Y         S1      
327m0078            VIA   -           A01X+121400Y+008300X0300Y         S1      
327m0078            PQ6   -D          A01X+126372Y+016070X3327Y4173R180 S1      
327m0078            PQ35  -D          A01X+126372Y+011630X3327Y4173R180 S1      
327m0078            PR315 -2A         A01X+120814Y+011630X1260Y2700R180 S1      
327m0078            PQ36  -D          A01X+126372Y+007190X3327Y4173R180 S1      
317m0078            VIA   -    MD0100PA00X+124020Y+016670X0200Y    R180 S0      
317m0078            VIA   -    MD0100PA00X+124020Y+016370X0200Y    R180 S0      
317m0078            VIA   -    MD0100PA00X+124020Y+016070X0200Y    R180 S0      
317m0078            VIA   -    MD0100PA00X+124020Y+015770X0200Y    R180 S0      
317m0078            VIA   -    MD0100PA00X+124020Y+015470X0200Y    R180 S0      
317m0078            VIA   -    MD0100PA00X+123720Y+015470X0200Y    R180 S0      
317m0078            VIA   -    MD0100PA00X+123720Y+015770X0200Y    R180 S0      
317m0078            VIA   -    MD0100PA00X+123720Y+016070X0200Y    R180 S0      
317m0078            VIA   -    MD0100PA00X+123720Y+016370X0200Y    R180 S0      
317m0078            VIA   -    MD0100PA00X+123720Y+016670X0200Y    R180 S0      
317m0078            VIA   -    MD0100PA00X+124020Y+012230X0200Y    R180 S0      
317m0078            VIA   -    MD0100PA00X+124020Y+011930X0200Y    R180 S0      
317m0078            VIA   -    MD0100PA00X+124020Y+011630X0200Y    R180 S0      
317m0078            VIA   -    MD0100PA00X+124020Y+011330X0200Y    R180 S0      
317m0078            VIA   -    MD0100PA00X+124020Y+011030X0200Y    R180 S0      
317m0078            VIA   -    MD0100PA00X+123720Y+011030X0200Y    R180 S0      
317m0078            VIA   -    MD0100PA00X+123720Y+011330X0200Y    R180 S0      
317m0078            VIA   -    MD0100PA00X+123720Y+011630X0200Y    R180 S0      
317m0078            VIA   -    MD0100PA00X+123720Y+011930X0200Y    R180 S0      
317m0078            VIA   -    MD0100PA00X+123720Y+012230X0200Y    R180 S0      
317m0078            VIA   -    MD0100PA00X+123420Y+011030X0200Y    R180 S0      
317m0078            VIA   -    MD0100PA00X+123420Y+011330X0200Y    R180 S0      
317m0078            VIA   -    MD0100PA00X+123420Y+011630X0200Y    R180 S0      
317m0078            VIA   -    MD0100PA00X+123420Y+011930X0200Y    R180 S0      
317m0078            VIA   -    MD0100PA00X+123420Y+012230X0200Y    R180 S0      
317m0078            VIA   -    MD0100PA00X+123120Y+007790X0200Y    R180 S0      
317m0078            VIA   -    MD0100PA00X+123120Y+007490X0200Y    R180 S0      
317m0078            VIA   -    MD0100PA00X+123120Y+007190X0200Y    R180 S0      
317m0078            VIA   -    MD0100PA00X+123120Y+006890X0200Y    R180 S0      
317m0078            VIA   -    MD0100PA00X+123120Y+006590X0200Y    R180 S0      
317m0078            VIA   -    MD0100PA00X+123420Y+007790X0200Y    R180 S0      
317m0078            VIA   -    MD0100PA00X+123420Y+007490X0200Y    R180 S0      
317m0078            VIA   -    MD0100PA00X+123420Y+007190X0200Y    R180 S0      
317m0078            VIA   -    MD0100PA00X+123420Y+006890X0200Y    R180 S0      
317m0078            VIA   -    MD0100PA00X+123420Y+006590X0200Y    R180 S0      
317m0078            VIA   -    MD0100PA00X+123720Y+007790X0200Y    R180 S0      
317m0078            VIA   -    MD0100PA00X+123720Y+007490X0200Y    R180 S0      
317m0078            VIA   -    MD0100PA00X+123720Y+007190X0200Y    R180 S0      
317m0078            VIA   -    MD0100PA00X+123720Y+006890X0200Y    R180 S0      
317m0078            VIA   -    MD0100PA00X+123720Y+006590X0200Y    R180 S0      
317m0078            VIA   -    MD0100PA00X+124020Y+006590X0200Y    R180 S0      
317m0078            VIA   -    MD0100PA00X+124020Y+006890X0200Y    R180 S0      
317m0078            VIA   -    MD0100PA00X+124020Y+007190X0200Y    R180 S0      
317m0078            VIA   -    MD0100PA00X+124020Y+007490X0200Y    R180 S0      
317m0078            VIA   -    MD0100PA00X+124020Y+007790X0200Y    R180 S0      
327P52V_HS1_TEMPP   PR6967-1          A01X+125358Y+033700X0180Y0200     S1      
317P52V_HS1_TEMPP   VIA   -    M      A01X+125598Y+033700X0200Y         S2      
017P52V_HS1_TEMPP   VIA   -    M      A10X+125598Y+033700X0260Y         S2      
017P52V_HS1_TEMPP         -    MD0100PA00X+125598Y+033700                       
317P52V_HS1_TEMPP   VIA   -    MD0100PA00X+107018Y+030398X0200Y         S0      
327P52V_HS1_TEMPP   PC589 -1   M      A10X+107018Y+030100X0198Y0197     S2      
327P52V_HS1_TEMPP   PU7   -44         A10X+106852Y+028758X0120Y0330     S2      
317m0079            VIA   -    M      A01X+132035Y+028990X0200Y         S2      
017m0079            VIA   -    M      A10X+132035Y+028990X0260Y         S2      
017m0079                  -    MD0100PA00X+132035Y+028990                       
327m0079            PR474 -1          A01X+131745Y+028990X0280Y0320R180 S1      
317m0079            VIA   -    MD0100PA00X+132035Y+024550X0200Y         S0      
327m0079            PR475 -1          A01X+131745Y+024550X0280Y0320R180 S1      
327m0079            R5860 -1   M      A10X+132410Y+020098X0198Y0197R090 S2      
327m0079            R5862 -1          A10X+132810Y+020098X0198Y0197R090 S2      
317m0079            VIA   -    MD0100PA00X+132035Y+020110X0200Y         S0      
327m0079            PR476 -1          A01X+131745Y+020110X0280Y0320R180 S1      
317m0080            VIA   -    MD0100PA00X+119928Y+011412X0200Y         S0      
327m0080            PR315 -2B         A01X+120234Y+011630X0100Y0200     S1      
327m0080            PR6954-2          A01X+121050Y+014930X0280Y0320R270 S1      
327m0080            PR6965-1   M      A01X+121050Y+014230X0280Y0320R090 S1      
327m0080            PR6959-2   M      A01X+121050Y+013530X0280Y0320R270 S1      
317m0080            VIA   -    M      A01X+121050Y+013240X0200Y         S2      
017m0080            VIA   -    M      A10X+121050Y+013240X0260Y         S2      
017m0080                  -    MD0100PA00X+121050Y+013240                       
327P52V_HS1_GATE5   VIA   -           A01X+132390Y+006210X0300Y         S1      
327P52V_HS1_GATE5   PR478 -2   M      A01X+131745Y+006210X0280Y0320R180 S1      
327P52V_HS1_GATE5   PQ36  -G          A01X+129995Y+006190X0520Y1220R090 S1      
327m0081            VIA   -    M      A10X+118241Y+028624X0260Y         S2      
327m0081            PR26  -2   M      A10X+134060Y+019432X0180Y0200R270 S2      
327m0081            PR220 -1   M      A10X+134480Y+019370X0280Y0320     S2      
317m0081            VIA   -    MD0100PA00X+133267Y+019064X0200Y         S0      
327m0081            R5862 -2   M      A10X+132810Y+019782X0198Y0197R090 S2      
327m0081            PD15  -1   M      A10X+133410Y+019460X0320Y0340R090 S2      
327m0081            PC82  -1          A10X+134450Y+018890X0280Y0320R180 S2      
317m0081            VIA   -    MD0100PA00X+120104Y+031891X0200Y         S0      
327m0081            PU1   -3          A10X+116899Y+028289X0110Y0300R090 S2      
327P52V_HS1_GATE6   VIA   -           A01X+132400Y+015600X0300Y         S1      
327P52V_HS1_GATE6   PR16  -2   M      A01X+131745Y+015090X0280Y0320R180 S1      
327P52V_HS1_GATE6   PQ6   -G          A01X+129995Y+015070X0520Y1220R090 S1      
327P52V_HS1_GATE1   VIA   -           A01X+132300Y+028410X0300Y         S1      
327P52V_HS1_GATE1   PR474 -2   M      A01X+131745Y+028410X0280Y0320R180 S1      
327P52V_HS1_GATE1   PQ32  -G          A01X+129995Y+028390X0520Y1220R090 S1      
327m0082            R5860 -2          A10X+132410Y+019782X0198Y0197R090 S2      
317m0082            VIA   -    MD0100PA00X+132410Y+019490X0200Y         S0      
327m0082            PU7   -32         A10X+104805Y+027695X0120Y0330R090 S2      
317m0082            VIA   -    M      A01X+104490Y+027860X0300Y         S1      
017m0082            VIA   -    M      A10X+104490Y+027860X0200Y         S1      
017m0082                  -    MD0100PA00X+104490Y+027860                       
327m0082            R5861 -1          A10X+132410Y+015342X0198Y0197R270 S2      
317m0082            VIA   -    MD0100PA00X+132410Y+015050X0200Y         S0      
327m0083            PU1   -8          A10X+116899Y+026714X0110Y0300R090 S2      
327m0083            PR5864-2   M      A01X+120058Y+015530X0198Y0197     S1      
327m0083            PR6954-1          A01X+120470Y+014930X0280Y0320R270 S1      
317m0083            VIA   -    M      A01X+120058Y+016028X0300Y         S1      
017m0083            VIA   -    M      A10X+120058Y+016028X0200Y         S1      
017m0083                  -    MD0100PA00X+120058Y+016028                       
327m0084            PU1   -5          A10X+116899Y+027305X0110Y0300R090 S2      
317m0084            VIA   -    M      A01X+120150Y+029328X0300Y         S1      
017m0084            VIA   -    M      A10X+120150Y+029328X0200Y         S1      
017m0084                  -    MD0100PA00X+120150Y+029328                       
327m0084            PR7040-2   M      A01X+120058Y+028850X0198Y0197     S1      
327m0084            PR6957-1          A01X+120470Y+028250X0280Y0320R270 S1      
327m0085            PU1   -6          A10X+116899Y+027108X0110Y0300R090 S2      
317m0085            VIA   -    M      A01X+119650Y+029328X0300Y         S1      
017m0085            VIA   -    M      A10X+119650Y+029328X0200Y         S1      
017m0085                  -    MD0100PA00X+119650Y+029328                       
327m0085            PR7040-1   M      A01X+119742Y+028850X0198Y0197     S1      
327m0085            PR6956-1          A01X+119350Y+028250X0280Y0320R090 S1      
317m0086            VIA   -    MD0100PA00X+119928Y+011848X0200Y         S0      
327m0086            PR315 -1B         A01X+119622Y+011630X0100Y0200     S1      
327m0086            PR6955-2          A01X+118770Y+014930X0280Y0320R090 S1      
327m0086            PR6964-1   M      A01X+118770Y+014230X0280Y0320R270 S1      
327m0086            PR6961-2   M      A01X+118770Y+013530X0280Y0320R090 S1      
317m0086            VIA   -    MD0100PA00X+118770Y+013240X0200Y         S2      
327m0087            PU1   -27         A10X+114221Y+028092X0110Y0300R090 S2      
327m0087            VIA   -    M      A10X+113160Y+028300X0260Y         S2      
327m0087            R5869 -2          A10X+112718Y+028300X0198Y0197R180 S2      
327m0088            PC585 -1          A10X+134960Y+014950X0280Y0320R270 S2      
327m0088            PR6999-2          A10X+134480Y+015560X0280Y0320     S2      
327m0088            VIA   -    M      A10X+135000Y+015480X0260Y         S2      
327m0089            PR6998-1          A10X+134010Y+015328X0180Y0200R270 S2      
327m0089            VIA   -           A10X+134550Y+016550X0260Y         S2      
327m0089            PD16  -2          A10X+133410Y+015880X0320Y0340R270 S2      
327m0089            PC583 -2   M      A10X+134120Y+016030X0280Y0320R090 S2      
327P52V_HS1_SCK     PU1   -25         A10X+114221Y+027698X0110Y0300R090 S2      
327P52V_HS1_SCK     VIA   -    M      A01X+113310Y+027770X0300Y         S1      
317P52V_HS1_SCK     VIA   -    MD0100PA00X+113211Y+027450X0200Y         S0      
327P52V_HS1_SCK     PR28  -1          A10X+112318Y+027450X0198Y0197     S2      
327P52V_HS1_SCK     PR27  -2   M      A10X+112710Y+027458X0198Y0197R270 S2      
317P52V_HS1_SCK     VIA   -    MD0100PA00X+113051Y+030772X0200Y         S0      
327P52V_HS1_SCK     U31   -6          A10X+112158Y+030772X0150Y0460R090 S2      
327P52V_HS1_CS      PU1   -26         A10X+114221Y+027895X0110Y0300R090 S2      
327P52V_HS1_CS      VIA   -    M      A10X+113346Y+027727X0260Y         S2      
317P52V_HS1_CS      VIA   -    MD0100PA00X+114160Y+031284X0200Y         S0      
327P52V_HS1_CS      U31   -1          A10X+114562Y+031284X0150Y0460R090 S2      
317P52V_HS1_CS      VIA   -    MD0100PA00X+113600Y+027895X0200Y         S0      
327P52V_HS1_CS      PR209 -2          A10X+112718Y+027850X0198Y0197R180 S2      
327P52V_HS1_SIO     PU1   -24         A10X+114221Y+027502X0110Y0300R090 S2      
327P52V_HS1_SIO     U31   -5          A10X+112158Y+030516X0150Y0460R090 S2      
317P52V_HS1_SIO     VIA   -    M      A01X+113198Y+026750X0300Y         S1      
017P52V_HS1_SIO     VIA   -    M      A10X+113198Y+026750X0200Y         S1      
017P52V_HS1_SIO           -    MD0100PA00X+113198Y+026750                       
327P52V_HS1_SIO     PR213 -1          A10X+112718Y+026750X0198Y0197     S2      
327P52V_HS1_SIO     PR212 -1   M      A10X+113418Y+027000X0198Y0197     S2      
317P52V_HS1_SIO     VIA   -    MD0100PA00X+113010Y+030517X0200Y         S0      
327P52V_HS1_SIO     U31   -2          A10X+114562Y+031028X0150Y0460R090 S2      
327P52V_HS1_TMR     PU1   -20         A10X+114221Y+026714X0110Y0300R090 S2      
327P52V_HS1_TMR     PC7   -1          A10X+112268Y+025850X0198Y0197     S2      
327P52V_HS1_TMR     PR210 -1   M      A10X+112710Y+025858X0198Y0197R090 S2      
327P52V_HS1_TMR     VIA   -    M      A10X+113460Y+025858X0260Y         S2      
327P52V_HS1_TEMP    PU1   -35         A10X+115265Y+028939X0110Y0300     S2      
317P52V_HS1_TEMP    VIA   -    MD0100PA00X+115714Y+030300X0200Y         S0      
327P52V_HS1_TEMP    VIA   -    M      A10X+115265Y+029466X0260Y         S2      
327P52V_HS1_TEMP    PC6   -1   M      A10X+115460Y+029942X0198Y0197R270 S2      
327P52V_HS1_TEMP    PR6966-1          A01X+124728Y+033700X0180Y0200R180 S1      
327P52V_HS1_DVCC    VIA   -           A10X+112000Y+032300X0260Y         S2      
327P52V_HS1_DVCC    VIA   -           A10X+112000Y+031750X0260Y         S2      
327P52V_HS1_DVCC    PU1   -15         A10X+115068Y+026261X0110Y0300     S2      
327P52V_HS1_DVCC    PC5   -2   M      A10X+115402Y+024950X0198Y0197     S2      
317P52V_HS1_DVCC    VIA   -    MD0100PA00X+115402Y+024700X0200Y         S0      
317P52V_HS1_DVCC    VIA   -    MD0100PA00X+112310Y+031950X0200Y         S0      
317P52V_HS1_DVCC    VIA   -           A01X+112310Y+032250X0300Y         S1      
017P52V_HS1_DVCC    VIA   -           A10X+112310Y+032250X0200Y         S1      
017P52V_HS1_DVCC          -     D0100PA00X+112310Y+032250                       
327P52V_HS1_DVCC    PC487 -1          A10X+112730Y+032100X0460Y0620     S2      
327P52V_HS1_DVCC    U31   -8          A10X+112158Y+031284X0150Y0460R090 S2      
327P52V_HS1_DVCC    U31   -7   M      A10X+112158Y+031028X0150Y0460R090 S2      
327P52V_HS1_DVCC    U31   -3          A10X+114562Y+030772X0150Y0460R090 S2      
327m0090            PR26  -1          A10X+134060Y+019748X0180Y0200R270 S2      
327m0090            VIA   -           A10X+134290Y+020960X0260Y         S2      
327m0090            PD15  -2          A10X+133410Y+020320X0320Y0340R270 S2      
327m0090            PC8   -2   M      A10X+134120Y+020440X0280Y0320R090 S2      
327P52V_HS1_VDSFB   PU1   -39         A10X+116643Y+028949X0110Y0280     S2      
327P52V_HS1_VDSFB   VIA   -           A10X+116737Y+029624X0260Y         S2      
327P52V_HS1_VDSFB   PR25  -2          A10X+116686Y+030300X0440Y0540R180 S2      
327HS1_TMR1         PR33  -1          A10X+112710Y+025058X0198Y0197R090 S2      
327HS1_TMR1         VIA   -    M      A10X+113260Y+025200X0260Y         S2      
327HS1_TMR1         PC551 -1          A10X+112268Y+025400X0198Y0197     S2      
327HS1_TMR1         PR210 -2   M      A10X+112710Y+025542X0198Y0197R090 S2      
327P52V_1_FUSE_1    PD7   -C          A10X+100700Y+019501X0950Y1300R270 S2      
327P52V_1_FUSE_1    PD9   -C          A10X+098050Y+019501X0950Y1300R270 S2      
327P52V_1_FUSE_1    FS5   -1          A10X+099400Y+017691X1280Y1350R090 S2      
327P52V_1_FUSE_1    R154  -1          A01X+102436Y+019050X0440Y0540R180 S1      
317P52V_1_FUSE_1    VIA   -    MD0100PA00X+100100Y+018500X0200Y         S0      
317P52V_1_FUSE_1    VIA   -    MD0100PA00X+102460Y+018500X0200Y         S0      
327P52V_1_FUSE_1    R398  -1   M      A10X+102460Y+018976X0440Y0540R090 S2      
317P52V_1_FUSE_1    VIA   -    MD0100PA00X+100700Y+018800X0200Y         S0      
317P52V_1_FUSE_1    VIA   -    MD0100PA00X+101000Y+018800X0200Y         S0      
317P52V_1_FUSE_1    VIA   -    MD0100PA00X+101300Y+018800X0200Y         S0      
317P52V_1_FUSE_1    VIA   -    M      A01X+101300Y+018500X0200Y         S2      
017P52V_1_FUSE_1    VIA   -    M      A10X+101300Y+018500X0260Y         S2      
017P52V_1_FUSE_1          -    MD0100PA00X+101300Y+018500                       
317P52V_1_FUSE_1    VIA   -    MD0100PA00X+101000Y+018500X0200Y         S0      
317P52V_1_FUSE_1    VIA   -    MD0100PA00X+100700Y+018500X0200Y         S0      
317P52V_1_FUSE_1    VIA   -    MD0100PA00X+100400Y+018800X0200Y         S0      
317P52V_1_FUSE_1    VIA   -    MD0100PA00X+100100Y+018800X0200Y         S0      
317P52V_1_FUSE_1    VIA   -    MD0100PA00X+100400Y+018500X0200Y         S0      
317P52V_1_FUSE_1    VIA   -    MD0100PA00X+097450Y+018800X0200Y         S0      
317P52V_1_FUSE_1    VIA   -    MD0100PA00X+097750Y+018800X0200Y         S0      
317P52V_1_FUSE_1    VIA   -    MD0100PA00X+098050Y+018800X0200Y         S0      
317P52V_1_FUSE_1    VIA   -    MD0100PA00X+097750Y+018500X0200Y         S0      
317P52V_1_FUSE_1    VIA   -    M      A01X+097450Y+018500X0200Y         S2      
017P52V_1_FUSE_1    VIA   -    M      A10X+097450Y+018500X0260Y         S2      
017P52V_1_FUSE_1          -    MD0100PA00X+097450Y+018500                       
317P52V_1_FUSE_1    VIA   -    M      A01X+098050Y+018500X0300Y         S1      
017P52V_1_FUSE_1    VIA   -    M      A10X+098050Y+018500X0200Y         S1      
017P52V_1_FUSE_1          -    MD0100PA00X+098050Y+018500                       
317P52V_1_FUSE_1    VIA   -    MD0100PA00X+098350Y+018800X0200Y         S0      
317P52V_1_FUSE_1    VIA   -    MD0100PA00X+098350Y+018500X0200Y         S0      
317P52V_1_FUSE_1    VIA   -    MD0100PA00X+098650Y+018800X0200Y         S0      
317P52V_1_FUSE_1    VIA   -    MD0100PA00X+098650Y+018500X0200Y         S0      
327m0091            PR212 -2          A10X+113102Y+027000X0198Y0197     S2      
327m0091            PR27  -1   M      A10X+112710Y+027142X0198Y0197R270 S2      
317m0091            VIA   -    MD0100PA00X+112460Y+027142X0200Y         S0      
327m0091            PR214 -2          A10X+114010Y+024642X0198Y0197R090 S2      
317m0091            VIA   -    M      A01X+114010Y+024400X0300Y         S1      
017m0091            VIA   -    M      A10X+114010Y+024400X0200Y         S1      
017m0091                  -    MD0100PA00X+114010Y+024400                       
317m0091            VIA   -    M      A01X+114560Y+024402X0300Y         S1      
017m0091            VIA   -    M      A10X+114560Y+024402X0200Y         S1      
017m0091                  -    MD0100PA00X+114560Y+024402                       
327m0091            R156  -1          A10X+114960Y+024642X0198Y0197R270 S2      
327m0091            R157  -1   M      A10X+114560Y+024642X0198Y0197R270 S2      
327m0091            PU1   -13         A10X+115462Y+026261X0110Y0300     S2      
327m0091            PC4   -1   M      A01X+114958Y+025150X0198Y0197R180 S1      
317m0091            VIA   -    M      A01X+115620Y+025890X0300Y         S1      
017m0091            VIA   -    M      A10X+115620Y+025890X0200Y         S1      
017m0091                  -    MD0100PA00X+115620Y+025890                       
327HS1_TMR2         PC83  -1          A10X+112200Y+024850X0280Y0320R090 S2      
327HS1_TMR2         PR211 -1   M      A10X+112068Y+024350X0198Y0197     S2      
327HS1_TMR2         VIA   -    M      A10X+112710Y+024250X0260Y         S2      
327HS1_TMR2         PR33  -2          A10X+112710Y+024742X0198Y0197R090 S2      
317m0092            VIA   -    MD0100PA00X+111800Y+030350X0200Y         S0      
327m0092            PC11  -2   M      A01X+112040Y+030050X0280Y0320R270 S1      
327m0092            PC6   -2          A10X+115460Y+030258X0198Y0197R270 S2      
327m0092            PR24  -2          A10X+115452Y+030650X0198Y0197     S2      
327m0092            PR36  -2          A01X+110818Y+030050X0198Y0197     S1      
317m0092            VIA   -    MD0100PA00X+111110Y+030050X0200Y         S0      
327m0092            PU1   -33         A10X+114871Y+028939X0110Y0300     S2      
327m0092            PU1   -34         A10X+115068Y+028939X0110Y0300     S2      
317m0092            VIA   -    MD0100PA00X+112110Y+029600X0200Y         S0      
327m0092            PC12  -2   M      A01X+111818Y+029600X0198Y0197     S1      
317m0092            VIA   -    MD0100PA00X+111110Y+028500X0200Y         S0      
327m0092            R374  -2   M      A01X+110818Y+028500X0198Y0197     S1      
327m0092            R373  -2   M      A01X+110818Y+029150X0198Y0197     S1      
317m0092            VIA   -    MD0100PA00X+111110Y+029150X0200Y         S0      
327m0092            PR209 -1          A10X+112402Y+027850X0198Y0197R180 S2      
327m0092            PR28  -2          A10X+112002Y+027450X0198Y0197     S2      
327m0092            PR37  -2          A01X+110502Y+029600X0198Y0197R180 S1      
317m0092            VIA   -    MD0100PA00X+110260Y+029600X0200Y         S0      
327m0092            PC590 -2          A10X+109918Y+029350X0198Y0197R180 S2      
327m0092            PR20  -2          A10X+110118Y+028500X0198Y0197R180 S2      
327m0092            PR21  -2          A10X+109918Y+029750X0198Y0197R180 S2      
327m0092            PC591 -2          A10X+109700Y+027800X0280Y0320R270 S2      
327m0092            PU1   -14         A10X+115265Y+026261X0110Y0300     S2      
317m0092            VIA   -    MD0100PA00X+115780Y+031205X0200Y         S0      
327m0092            PJ1   -1   M      A10X+115460Y+031205X0280Y0740R180 S2      
317m0092            VIA   -    MD0100PA00X+115760Y+028500X0200Y         S0      
317m0092            VIA   -    MD0100PA00X+114610Y+028500X0200Y         S0      
317m0092            VIA   -    MD0100PA00X+114610Y+027600X0200Y         S0      
317m0092            VIA   -    MD0100PA00X+115760Y+027600X0200Y         S0      
317m0092            VIA   -    MD0100PA00X+115760Y+026700X0200Y         S0      
317m0092            VIA   -    MD0100PA00X+114610Y+026700X0200Y         S0      
327m0092            PU1   -40  M      A10X+115216Y+027600X1437Y2126     S2      
327m0092            PC5   -1          A10X+115718Y+024950X0198Y0197     S2      
327m0092            PC551 -2          A10X+111952Y+025400X0198Y0197     S2      
327m0092            PC7   -2          A10X+111952Y+025850X0198Y0197     S2      
327m0092            PR213 -2          A10X+112402Y+026750X0198Y0197     S2      
327m0092            PR211 -2          A10X+111752Y+024350X0198Y0197     S2      
327m0092            PR11  -1          A10X+112402Y+026350X0198Y0197R180 S2      
327m0092            PC83  -2          A10X+111620Y+024850X0280Y0320R090 S2      
327m0092            PR35  -2          A10X+109768Y+025150X0198Y0197R180 S2      
327m0092            R149  -2          A10X+107368Y+024550X0198Y0197R180 S2      
327m0092            R159  -2          A10X+114560Y+023792X0198Y0197R090 S2      
327m0092            R158  -2          A10X+114960Y+023792X0198Y0197R090 S2      
327m0092            PC3   -2          A10X+115580Y+023950X0460Y0620R180 S2      
327m0092            PU7   -19         A10X+106458Y+026042X0120Y0330     S2      
327m0092            PR6932-2          A10X+106152Y+024550X0198Y0197     S2      
327m0092            PC13  -2   M      A10X+105610Y+024700X0400Y0500     S2      
327m0092            PU7   -PAD1M      A10X+107107Y+027400X1100Y2200     S2      
317m0092            VIA   -    MD0100PA00X+106670Y+028390X0200Y         S0      
317m0092            VIA   -    MD0100PA00X+106660Y+026410X0200Y         S0      
317m0092            VIA   -    MD0100PA00X+107550Y+028390X0200Y         S0      
317m0092            VIA   -    MD0100PA00X+106670Y+027400X0200Y         S0      
317m0092            VIA   -    MD0100PA00X+107550Y+027400X0200Y         S0      
317m0092            VIA   -    MD0100PA00X+107550Y+026410X0200Y         S0      
327m0092            PC9   -2          A10X+109010Y+030258X0198Y0197R270 S2      
327m0092            PC586 -2          A10X+107810Y+030258X0198Y0197R270 S2      
327m0092            PC575 -2          A10X+108610Y+030258X0198Y0197R270 S2      
327m0092            PR6931-2          A10X+107410Y+030258X0198Y0197R270 S2      
327m0092            PR482 -2          A10X+108210Y+030258X0198Y0197R270 S2      
327m0092            PC587 -2          A10X+105510Y+031280X0460Y0620R090 S2      
327m0092            PR483 -2   M      A01X+106652Y+030750X0198Y0197R180 S1      
327m0092            PC576 -2   M      A01X+106652Y+031150X0198Y0197R180 S1      
327m0092            PC10  -2   M      A10X+106260Y+030258X0198Y0197R270 S2      
317m0092            VIA   -    MD0100PA00X+106260Y+030500X0200Y         S0      
327m0092            PR6969-2          A01X+124728Y+033000X0180Y0200     S1      
317m0092            VIA   -    M      A01X+124487Y+033000X0200Y         S2      
017m0092            VIA   -    M      A10X+124487Y+033000X0260Y         S2      
017m0092                  -    MD0100PA00X+124487Y+033000                       
327m0093            PR6966-2          A01X+125042Y+033700X0180Y0200R180 S1      
327m0093            PR6967-2   M      A01X+125042Y+033700X0180Y0200     S1      
327m0093            VIA   -           A01X+126310Y+034320X0300Y         S1      
327m0093            PQ37  -B   M      A01X+126310Y+033750X0400Y0500R270 S1      
327m0093            PQ37  -C          A01X+127190Y+033350X0400Y0500R270 S1      
327P52V_HS2_FB      PR7005-2          A10X+060134Y+023500X0440Y0540     S2      
327P52V_HS2_FB      VIA   -           A10X+060220Y+025320X0260Y         S2      
327P52V_HS2_FB      PU8   -38         A10X+060373Y+026261X0110Y0300R180 S2      
327P52V_HS2_FB      PR7010-1          A10X+060461Y+024550X0198Y0197R180 S2      
327P52V_HS1_FB      VIA   -           A10X+116020Y+029980X0260Y         S2      
327P52V_HS1_FB      PU1   -38         A10X+115855Y+028939X0110Y0300     S2      
327P52V_HS1_FB      PR23  -2          A10X+116686Y+031200X0440Y0540R180 S2      
327P52V_HS1_FB      PR24  -1          A10X+115768Y+030650X0198Y0197     S2      
327P52V_HS1_MODE    PU1   -19         A10X+114211Y+026517X0110Y0280R090 S2      
327P52V_HS1_MODE    PR214 -1          A10X+114010Y+024958X0198Y0197R090 S2      
327P52V_HS1_MODE    VIA   -    M      A10X+114010Y+025450X0260Y         S2      
327m0094            PR7002-2          A10X+041750Y+021940X0280Y0320     S2      
327m0094            VIA   -    M      A10X+041200Y+021930X0260Y         S2      
327m0094            PC596 -1          A10X+041240Y+021400X0280Y0320R090 S2      
327P52V_HS1_CLKIN   PU1   -21         A10X+114221Y+026911X0110Y0300R090 S2      
327P52V_HS1_CLKIN   VIA   -    M      A10X+113170Y+026300X0260Y         S2      
327P52V_HS1_CLKIN   PR11  -2          A10X+112718Y+026350X0198Y0197R180 S2      
317P52V_HS2_SIO     VIA   -    MD0100PA00X+064450Y+024684X0200Y    R180 S0      
327P52V_HS2_SIO     U32   -5   M      A10X+064070Y+024684X0150Y0460R270 S2      
327P52V_HS2_SIO     U32   -2          A10X+061667Y+024172X0150Y0460R270 S2      
327P52V_HS2_SIO     PR7007-1          A10X+063511Y+028450X0198Y0197R180 S2      
317P52V_HS2_SIO     VIA   -    M      A01X+063031Y+028450X0300Y    R180 S1      
017P52V_HS2_SIO     VIA   -    M      A10X+063031Y+028450X0200Y    R180 S1      
017P52V_HS2_SIO           -    MD0100PA00X+063031Y+028450                       
327P52V_HS2_SIO     PU8   -24         A10X+062007Y+027698X0110Y0300R270 S2      
327P52V_HS2_SIO     PR7006-1   M      A10X+062811Y+028200X0198Y0197R180 S2      
327m0095            PR220 -2          A10X+134480Y+019950X0280Y0320     S2      
327m0095            VIA   -    M      A10X+135010Y+019925X0260Y         S2      
327m0095            PC584 -1          A10X+134960Y+019400X0280Y0320R270 S2      
327m0096            PU1   -29         A10X+114221Y+028486X0110Y0300R090 S2      
327m0096            VIA   -    M      A10X+113260Y+029200X0260Y         S2      
327m0096            R5856 -2          A10X+112718Y+029200X0198Y0197R180 S2      
327m0097            PU1   -28         A10X+114221Y+028289X0110Y0300R090 S2      
327m0097            VIA   -    M      A10X+113626Y+028534X0260Y         S2      
327m0097            R5855 -2          A10X+112718Y+028750X0198Y0197R180 S2      
327m0098            R5872 -2          A10X+063511Y+026000X0198Y0197     S2      
327m0098            VIA   -    M      A10X+062968Y+026000X0260Y    R180 S2      
327m0098            PU8   -29         A10X+062007Y+026714X0110Y0300R270 S2      
327m0099            R5871 -2          A10X+063511Y+026450X0198Y0197     S2      
327m0099            VIA   -    M      A10X+062603Y+026666X0260Y    R180 S2      
327m0099            PU8   -28         A10X+062007Y+026911X0110Y0300R270 S2      
327m0100            PR6994-2          A01X+051186Y+032200X0180Y0200     S1      
327m0100            PR6995-2   M      A01X+051186Y+032200X0180Y0200R180 S1      
327m0100            VIA   -           A01X+048410Y+032550X0300Y         S1      
327m0100            PQ44  -C   M      A01X+049038Y+032550X0400Y0500R090 S1      
327m0100            PQ44  -B   M      A01X+049918Y+032150X0400Y0500R090 S1      
327HS2_TMR2         PC602 -1          A10X+064028Y+030350X0280Y0320R270 S2      
327HS2_TMR2         PR7011-1   M      A10X+064152Y+030850X0198Y0197R180 S2      
327HS2_TMR2         VIA   -    M      A10X+063560Y+030942X0260Y         S2      
327HS2_TMR2         PR7009-2          A10X+063518Y+030458X0198Y0197R270 S2      
327P52V_HS2_TMR     PC603 -1          A10X+063961Y+029350X0198Y0197R180 S2      
327P52V_HS2_TMR     PR7008-1   M      A10X+063518Y+029342X0198Y0197R270 S2      
327P52V_HS2_TMR     VIA   -    M      A10X+062768Y+029342X0260Y    R180 S2      
327P52V_HS2_TMR     PU8   -20         A10X+062007Y+028486X0110Y0300R270 S2      
327m0101            PR7000-1          A10X+042200Y+021758X0180Y0200R270 S2      
327m0101            VIA   -           A10X+041850Y+022960X0260Y         S2      
327m0101            PD17  -2          A10X+042810Y+022330X0320Y0340R270 S2      
327m0101            PC592 -2   M      A10X+042100Y+022450X0280Y0320R270 S2      
327P52V_HS2_TEMP    PR6994-1          A01X+051501Y+032200X0180Y0200     S1      
317P52V_HS2_TEMP    VIA   -    M      A01X+051741Y+032200X0200Y         S2      
017P52V_HS2_TEMP    VIA   -    M      A10X+051741Y+032200X0260Y         S2      
017P52V_HS2_TEMP          -    MD0100PA00X+051741Y+032200                       
317P52V_HS2_TEMP    VIA   -    MD0100PA00X+060964Y+025452X0200Y         S0      
327P52V_HS2_TEMP    PC601 -1          A10X+060768Y+025258X0198Y0197R090 S2      
327P52V_HS2_TEMP    PU8   -35         A10X+060964Y+026261X0110Y0300R180 S2      
327HS2_TMR1         PR7009-1          A10X+063518Y+030142X0198Y0197R270 S2      
327HS2_TMR1         VIA   -    M      A10X+062968Y+030000X0260Y    R180 S2      
327HS2_TMR1         PC604 -1          A10X+063961Y+029800X0198Y0197R180 S2      
327HS2_TMR1         PR7008-2   M      A10X+063518Y+029658X0198Y0197R270 S2      
327P52V_HS2_CLKIN   PR7013-2          A10X+063511Y+028850X0198Y0197     S2      
327P52V_HS2_CLKIN   VIA   -    M      A10X+062718Y+028750X0260Y    R180 S2      
327P52V_HS2_CLKIN   PU8   -21         A10X+062007Y+028289X0110Y0300R270 S2      
327P52V_HS2_VDSFB   VIA   -           A10X+059400Y+025700X0260Y         S2      
327P52V_HS2_VDSFB   PU8   -39         A10X+059586Y+026251X0110Y0280R180 S2      
327P52V_HS2_VDSFB   PR7004-2          A10X+059460Y+025124X0440Y0540R090 S2      
327P52V_HS2_DVCC    VIA   -           A10X+064150Y+023200X0260Y         S2      
317P52V_HS2_DVCC    VIA   -    M      A01X+063901Y+023638X0300Y    R180 S1      
017P52V_HS2_DVCC    VIA   -    M      A10X+063901Y+023638X0200Y    R180 S1      
017P52V_HS2_DVCC          -    MD0100PA00X+063901Y+023638                       
327P52V_HS2_DVCC    U32   -3          A10X+061667Y+024428X0150Y0460R270 S2      
327P52V_HS2_DVCC    U32   -8          A10X+064070Y+023916X0150Y0460R270 S2      
327P52V_HS2_DVCC    U32   -7   M      A10X+064070Y+024172X0150Y0460R270 S2      
327P52V_HS2_DVCC    PC605 -1          A10X+063498Y+023100X0460Y0620R180 S2      
317P52V_HS2_DVCC    VIA   -    M      A01X+060826Y+030500X0300Y    R180 S1      
017P52V_HS2_DVCC    VIA   -    M      A10X+060826Y+030500X0200Y    R180 S1      
017P52V_HS2_DVCC          -    MD0100PA00X+060826Y+030500                       
327P52V_HS2_DVCC    PC600 -2   M      A10X+060826Y+030250X0198Y0197R180 S2      
327P52V_HS2_DVCC    PU8   -15         A10X+061160Y+028939X0110Y0300R180 S2      
327P52V_HS2_MODE    PR7016-1          A10X+062218Y+030242X0198Y0197R270 S2      
327P52V_HS2_MODE    VIA   -    M      A10X+062200Y+029750X0260Y    R180 S2      
327P52V_HS2_MODE    PU8   -19         A10X+062017Y+028683X0110Y0280R270 S2      
317P52V_HS2_CS      VIA   -    MD0100PA00X+062060Y+023916X0200Y         S0      
327P52V_HS2_CS      U32   -1          A10X+061667Y+023916X0150Y0460R270 S2      
317P52V_HS2_CS      VIA   -    M      A01X+062568Y+027350X0300Y         S1      
017P52V_HS2_CS      VIA   -    M      A10X+062568Y+027350X0200Y         S1      
017P52V_HS2_CS            -    MD0100PA00X+062568Y+027350                       
327P52V_HS2_CS      PR7012-2          A10X+063511Y+027350X0198Y0197     S2      
327P52V_HS2_CS      PU8   -26         A10X+062007Y+027305X0110Y0300R270 S2      
327P52V_HS2_SCK     PR7015-1          A10X+063911Y+027750X0198Y0197R180 S2      
327P52V_HS2_SCK     PR7014-2   M      A10X+063518Y+027742X0198Y0197R090 S2      
317P52V_HS2_SCK     VIA   -    MD0100PA00X+062902Y+027750X0200Y    R180 S0      
327P52V_HS2_SCK     PU8   -25         A10X+062007Y+027502X0110Y0300R270 S2      
317P52V_HS2_SCK     VIA   -    M      A01X+064590Y+024220X0300Y    R180 S1      
017P52V_HS2_SCK     VIA   -    M      A10X+064590Y+024220X0200Y    R180 S1      
017P52V_HS2_SCK           -    MD0100PA00X+064590Y+024220                       
327P52V_HS2_SCK     U32   -6          A10X+064070Y+024428X0150Y0460R270 S2      
327m0102            PR7006-2          A10X+063126Y+028200X0198Y0197R180 S2      
317m0102            VIA   -    M      A01X+063768Y+028058X0300Y    R180 S1      
017m0102            VIA   -    M      A10X+063768Y+028058X0200Y    R180 S1      
017m0102                  -    MD0100PA00X+063768Y+028058                       
327m0102            PR7014-1   M      A10X+063518Y+028058X0198Y0197R090 S2      
317m0102            VIA   -    M      A01X+062218Y+030800X0300Y    R180 S1      
017m0102            VIA   -    M      A10X+062218Y+030800X0200Y    R180 S1      
017m0102                  -    MD0100PA00X+062218Y+030800                       
327m0102            PR7016-2          A10X+062218Y+030558X0198Y0197R270 S2      
317m0102            VIA   -    M      A01X+061668Y+030798X0300Y         S1      
017m0102            VIA   -    M      A10X+061668Y+030798X0200Y         S1      
017m0102                  -    MD0100PA00X+061668Y+030798                       
327m0102            R5873 -1          A10X+061268Y+030558X0198Y0197R090 S2      
327m0102            R5874 -1   M      A10X+061668Y+030558X0198Y0197R090 S2      
327m0102            PC599 -1   M      A01X+060458Y+030000X0198Y0197R180 S1      
317m0102            VIA   -    M      A01X+060608Y+029310X0300Y    R180 S1      
017m0102            VIA   -    M      A10X+060608Y+029310X0200Y    R180 S1      
017m0102                  -    MD0100PA00X+060608Y+029310                       
327m0102            PU8   -13         A10X+060767Y+028939X0110Y0300R180 S2      
317m0103            VIA   -    MD0100PA00X+161810Y+014892X0200Y         S0      
327m0103            R424  -2   M      A01X+162210Y+014892X0198Y0197R270 S1      
327m0103            U30   -G          A01X+162786Y+014906X0320Y0360     S1      
317m0103            VIA   -    M      A01X+039622Y+004688X0200Y         S2      
017m0103            VIA   -    M      A10X+039622Y+004688X0260Y         S2      
017m0103                  -    MD0100PA00X+039622Y+004688                       
327m0103            R163  -1   M      A01X+039200Y+004688X0198Y0197R270 S1      
327m0103            R162  -2          A01X+038706Y+005550X0440Y0540     S1      
327m0104            VIA   -    M      A01X+163516Y+020050X0300Y         S1      
327m0104            R160  -2          A01X+162884Y+020250X0440Y0540R180 S1      
327m0104            R161  -1          A01X+164100Y+020142X0198Y0197R090 S1      
327m0104            R420  -2   M      A01X+162960Y+019558X0198Y0197R090 S1      
327m0104            U29   -G   M      A01X+163516Y+019474X0320Y0360R270 S1      
327P52V_HS1_FLT     PU1   -36         A10X+115462Y+028939X0110Y0300     S2      
327P52V_HS1_FLT     R358  -2          A01X+108568Y+025550X0198Y0197     S1      
317P52V_HS1_FLT     VIA   -    MD0100PA00X+110010Y+024750X0200Y         S0      
327P52V_HS1_FLT     R151  -2          A10X+109768Y+024750X0198Y0197R180 S2      
317P52V_HS1_FLT     VIA   -    MD0100PA00X+115651Y+029540X0200Y         S0      
317P52V_HS1_FLT     VIA   -    MD0100PA00X+116300Y+035250X0200Y         S0      
327P52V_HS1_FLT     U8    -4          A01X+164350Y+017340X0140Y0590R270 S1      
317P52V_HS1_FLT     VIA   -    M      A01X+163660Y+017350X0300Y    R090 S1      
017P52V_HS1_FLT     VIA   -    M      A10X+163660Y+017350X0200Y    R090 S1      
017P52V_HS1_FLT           -    MD0100PA00X+163660Y+017350                       
317P52V_HS2_FLT     VIA   -    MD0100PA00X+060580Y+025650X0200Y         S0      
327P52V_HS2_FLT     PU8   -36         A10X+060767Y+026261X0110Y0300R180 S2      
327P52V_HS2_FLT     R5888 -2          A01X+067752Y+029850X0198Y0197R180 S1      
317P52V_HS2_FLT     VIA   -    MD0100PA00X+066210Y+030450X0200Y         S0      
327P52V_HS2_FLT     R5890 -2          A10X+066452Y+030450X0198Y0197     S2      
327P52V_HS2_FLT     U8    -5          A01X+164350Y+017084X0140Y0590R270 S1      
317P52V_HS2_FLT     VIA   -    M      A01X+166400Y+020250X0200Y         S2      
017P52V_HS2_FLT     VIA   -    M      A10X+166400Y+020250X0260Y         S2      
017P52V_HS2_FLT           -    MD0100PA00X+166400Y+020250                       
327m0105            PU1   -37         A10X+115658Y+028939X0110Y0300     S2      
317m0105            VIA   -    MD0100PA00X+115658Y+029249X0200Y         S0      
317m0105            VIA   -    M      A01X+116600Y+035250X0200Y         S2      
017m0105            VIA   -    M      A10X+116600Y+035250X0260Y         S2      
017m0105                  -    MD0100PA00X+116600Y+035250                       
317m0105            VIA   -    MD0100PA00X+162400Y+018900X0200Y         S0      
327m0105            R420  -1          A01X+162960Y+019242X0198Y0197R090 S1      
327P12V_FAN_LED     R5918 -1          A01X+163834Y+009094X0180Y0200     S1      
327P12V_FAN_LED     R5921 -1          A01X+162096Y+010808X0180Y0200R270 S1      
327P12V_FAN_LED     C96   -1          A01X+165146Y+010238X0180Y0200R180 S1      
317P12V_FAN_LED     J8    -S3  MD0295PA00X+147520Y+000801X0455Y    R270 S3      
317P12V_FAN_LED     J9    -S3   D0295PA00X+028465Y+000801X0455Y    R270 S3      
317P12V_FAN_LED     VIA   -    MD0100PA00X+164780Y+008020X0200Y         S0      
317P12V_FAN_LED     VIA   -    MD0100PA00X+164780Y+007720X0200Y         S0      
327P12V_FAN_LED     D5    -C          A01X+164117Y+007980X0670Y0990R090 S1      
317P12V_FAN_LED     VIA   -    MD0100PA00X+164780Y+008320X0200Y    R090 S0      
327P12V_FAN_LED     C95   -1          A10X+163674Y+009633X0400Y0500R180 S2      
327P12V_FAN_LED     VIA   -           A01X+164650Y+009400X0300Y    R090 S1      
317P12V_FAN_LED     VIA   -    MD0100PA00X+165104Y+009973X0200Y         S0      
317P12V_FAN_LED     VIA   -    MD0100PA00X+164704Y+010143X0200Y         S0      
317P12V_FAN_LED     VIA   -    MD0100PA00X+164554Y+010413X0200Y         S0      
327P12V_FAN_LED     U38   -17         A01X+164587Y+010769X0100Y0320R180 S1      
327P12V_FAN_LED     U38   -18         A01X+164784Y+010769X0100Y0320R180 S1      
327P12V_FAN_LED     U38   -19         A01X+164981Y+010769X0100Y0320R180 S1      
327P12V_FAN_LED     U38   -20         A01X+165177Y+010769X0100Y0320R180 S1      
327P12V_FAN_LED     U38   -15         A01X+164193Y+010769X0100Y0320R180 S1      
327P12V_FAN_LED     U38   -16         A01X+164390Y+010769X0100Y0320R180 S1      
317P12V_FAN_LED     VIA   -    MD0100PA00X+163854Y+010413X0200Y         S0      
317P12V_FAN_LED     VIA   -    MD0100PA00X+164004Y+010143X0200Y         S0      
317P12V_FAN_LED     VIA   -    MD0100PA00X+164354Y+010143X0200Y         S0      
317P12V_FAN_LED     VIA   -    MD0100PA00X+164204Y+010413X0200Y         S0      
327P12V_FAN_LED     U38   -13         A01X+163799Y+010769X0100Y0320R180 S1      
327P12V_FAN_LED     U38   -14         A01X+163996Y+010769X0100Y0320R180 S1      
327P3V3_HPDB_EN     R392  -2          A01X+177183Y+035230X0180Y0200     S1      
317P3V3_HPDB_EN     VIA   -    M      A01X+176770Y+034620X0200Y         S2      
017P3V3_HPDB_EN     VIA   -    M      A10X+176770Y+034620X0260Y         S2      
017P3V3_HPDB_EN           -    MD0100PA00X+176770Y+034620                       
327P3V3_HPDB_EN     R393  -1   M      A01X+177183Y+034829X0198Y0197     S1      
327P3V3_HPDB_EN     R394  -2   M      A01X+177170Y+034397X0198Y0197R180 S1      
327P3V3_HPDB_EN     PU5   -8          A01X+176273Y+034038X0070Y0320R270 S1      
317m0106            J11   -S16  D0410PA00X+184896Y+031421X0610Y    R090 S3      
317m0106            VIA   -    M      A01X+179560Y+030800X0200Y         S2      
017m0106            VIA   -    M      A10X+179560Y+030800X0260Y         S2      
017m0106                  -    MD0100PA00X+179560Y+030800                       
327m0106            R394  -1          A01X+177486Y+034397X0198Y0197R180 S1      
327P12V_HPDB        R392  -1          A01X+177498Y+035230X0180Y0200     S1      
327P12V_HPDB        C94   -1          A01X+166200Y+011158X0180Y0200R090 S1      
327P12V_HPDB        R5919 -1          A01X+162494Y+010808X0180Y0200R270 S1      
317P12V_HPDB        VIA   -    M      A01X+162537Y+010394X0200Y         S2      
017P12V_HPDB        VIA   -    M      A10X+162537Y+010394X0260Y         S2      
017P12V_HPDB              -    MD0100PA00X+162537Y+010394                       
327P12V_HPDB        R5920 -1          A01X+162896Y+009593X0280Y0320R270 S1      
327P12V_HPDB        PL1   -1          A01X+178006Y+039602X0420Y0990R180 S1      
317P12V_HPDB        J11   -S9  MD0410PA00X+184396Y+034921X0610Y    R090 S3      
317P12V_HPDB        J11   -S13 MD0410PA00X+184396Y+032921X0610Y    R090 S3      
317P12V_HPDB        J11   -S10 MD0410PA00X+184896Y+034421X0610Y    R090 S3      
317P12V_HPDB        VIA   -    MD0100PA00X+177884Y+038691X0200Y    R090 S0      
317P12V_HPDB        VIA   -    MD0100PA00X+177884Y+038951X0200Y    R090 S0      
317P12V_HPDB        VIA   -    MD0100PA00X+178154Y+038694X0200Y    R090 S0      
317P12V_HPDB        VIA   -    MD0100PA00X+178404Y+038694X0200Y    R090 S0      
317P12V_HPDB        VIA   -    MD0100PA00X+178154Y+038954X0200Y    R090 S0      
317P12V_HPDB        VIA   -    MD0100PA00X+178404Y+038954X0200Y    R090 S0      
317P12V_HPDB        VIA   -    MD0100PA00X+177884Y+040551X0200Y    R090 S0      
317P12V_HPDB        VIA   -    MD0100PA00X+178404Y+040554X0200Y    R090 S0      
317P12V_HPDB        VIA   -    MD0100PA00X+178154Y+040554X0200Y    R090 S0      
317P12V_HPDB        VIA   -    MD0100PA00X+177884Y+040291X0200Y    R090 S0      
317P12V_HPDB        VIA   -    MD0100PA00X+178404Y+040294X0200Y    R090 S0      
317P12V_HPDB        VIA   -    MD0100PA00X+178154Y+040294X0200Y    R090 S0      
317P12V_HPDB        VIA   -    MD0100PA00X+177738Y+035230X0200Y    R270 S0      
317P12V_HPDB        VIA   -    M      A01X+167580Y+012040X0200Y         S2      
017P12V_HPDB        VIA   -    M      A10X+167580Y+012040X0260Y         S2      
017P12V_HPDB              -    MD0100PA00X+167580Y+012040                       
317P12V_HPDB        VIA   -    M      A01X+166980Y+012040X0200Y         S2      
017P12V_HPDB        VIA   -    M      A10X+166980Y+012040X0260Y         S2      
017P12V_HPDB              -    MD0100PA00X+166980Y+012040                       
317P12V_HPDB        VIA   -    MD0100PA00X+167280Y+012040X0200Y         S0      
317P12V_HPDB        VIA   -    MD0100PA00X+164646Y+011445X0180Y         S0      
317P12V_HPDB        VIA   -    MD0100PA00X+165000Y+011445X0180Y         S0      
317P12V_HPDB        VIA   -    MD0100PA00X+166025Y+011676X0200Y         S0      
317P12V_HPDB        VIA   -    MD0100PA00X+165705Y+011386X0200Y         S0      
317P12V_HPDB        VIA   -    M      A01X+165705Y+011676X0200Y         S2      
017P12V_HPDB        VIA   -    M      A10X+165705Y+011676X0260Y         S2      
017P12V_HPDB              -    MD0100PA00X+165705Y+011676                       
317P12V_HPDB        VIA   -    MD0100PA00X+163937Y+011195X0180Y         S0      
317P12V_HPDB        VIA   -    MD0100PA00X+164292Y+011445X0180Y         S0      
327P12V_HPDB        D4    -C          A01X+167300Y+011465X0850Y0890R090 S1      
317P12V_HPDB        VIA   -    MD0100PA00X+166025Y+011386X0200Y         S0      
317P12V_HPDB        VIA   -    MD0100PA00X+165000Y+011195X0180Y         S0      
317P12V_HPDB        VIA   -    MD0100PA00X+164646Y+011195X0180Y         S0      
317P12V_HPDB        VIA   -    MD0100PA00X+163937Y+011445X0180Y         S0      
317P12V_HPDB        VIA   -    MD0100PA00X+164292Y+011195X0180Y         S0      
327P12V_HPDB        U38   -23         A01X+164823Y+011320X0100Y0500R180 S1      
327P12V_HPDB        U38   -24         A01X+164469Y+011320X0100Y0500R180 S1      
327P12V_HPDB        U38   -21_2       A01X+165310Y+011123X0364Y0492R180 S1      
327P12V_HPDB        U38   -25         A01X+164114Y+011320X0100Y0500R180 S1      
327P12V_HPDB        U38   -26         A01X+163760Y+011320X0100Y0500R180 S1      
327m0107            PC60  -1          A01X+175930Y+032290X0180Y0200R180 S1      
327m0107            PC617 -1          A01X+175839Y+036553X0400Y0500     S1      
327m0107            PC618 -1          A01X+175839Y+037323X0400Y0500     S1      
327m0107            PL1   -2          A01X+176569Y+039602X0420Y0990R180 S1      
327m0107            VIA   -           A01X+174900Y+041600X0300Y         S1      
327m0107            PC138 -1          A01X+175413Y+039250X0630Y1380R090 S1      
327m0107            PC59  -1          A01X+176560Y+036300X0400Y0500R180 S1      
327m0107            PU5   -21         A01X+175840Y+033054X0120Y0790R180 S1      
327m0107            PU5   -10         A01X+175840Y+034078X0120Y0790R180 S1      
327m0107            PC57  -1          A01X+175839Y+035013X0400Y0500     S1      
327m0107            PC56  -1          A01X+175839Y+035783X0400Y0500     S1      
327m0107            PC58  -1          A01X+176560Y+037000X0400Y0500R180 S1      
327P3V3_HPDB_REF    PC53  -1          A01X+177174Y+033232X0198Y0197     S1      
327P3V3_HPDB_REF    PU5   -5          A01X+176273Y+033566X0070Y0320R270 S1      
317P3V3_HPDB_REF    VIA   -    M      A01X+176969Y+033465X0200Y    R270 S2      
017P3V3_HPDB_REF    VIA   -    M      A10X+176969Y+033465X0260Y    R270 S2      
017P3V3_HPDB_REF          -    MD0100PA00X+176969Y+033465                       
317P3V3_HPDB_CS     VIA   -    M      A01X+176930Y+032940X0200Y         S2      
017P3V3_HPDB_CS     VIA   -    M      A10X+176930Y+032940X0260Y         S2      
017P3V3_HPDB_CS           -    MD0100PA00X+176930Y+032940                       
327P3V3_HPDB_CS     PR113 -1          A01X+177174Y+032832X0198Y0197     S1      
327P3V3_HPDB_CS     PU5   -3          A01X+176273Y+033251X0070Y0320R270 S1      
327m0108            PL2   -1          A01X+175988Y+031202X1280Y1380R270 S1      
327m0108            PC52  -2          A01X+177788Y+032270X0198Y0197     S1      
327m0108            PU5   -20         A01X+175604Y+033054X0120Y0790R180 S1      
327P3V3_HPDB_PG     VIA   -    M      A10X+174250Y+019800X0260Y         S2      
327P3V3_HPDB_PG     R5900 -2          A01X+175108Y+020050X0198Y0197     S1      
317P3V3_HPDB_PG     VIA   -    MD0100PA00X+175056Y+019800X0200Y         S0      
327P3V3_HPDB_PG     U36   -G          A01X+175056Y+019474X0320Y0360R270 S1      
327P3V3_HPDB_PG     R5941 -1          A10X+173592Y+018650X0198Y0197R180 S2      
327m0109            PR111 -2          A01X+177086Y+032267X0198Y0197     S1      
327m0109            PC52  -1          A01X+177472Y+032270X0198Y0197     S1      
327P3V3_HPDB_VCC    PU5   -19         A01X+175171Y+032896X0120Y0320R090 S1      
327P3V3_HPDB_VCC    PC55  -1          A01X+174610Y+032845X0198Y0197R090 S1      
327m0110            PU5   -1          A01X+176253Y+032896X0354Y0118R180 S1      
327m0110            PR111 -1          A01X+176770Y+032267X0198Y0197     S1      
317P3V3_HPDB_FB     VIA   -    M      A01X+176930Y+034060X0200Y         S2      
017P3V3_HPDB_FB     VIA   -    M      A10X+176930Y+034060X0260Y         S2      
017P3V3_HPDB_FB           -    MD0100PA00X+176930Y+034060                       
327P3V3_HPDB_FB     PU5   -7          A01X+176273Y+033881X0070Y0320R270 S1      
327P3V3_HPDB_FB     PR114 -1   M      A01X+177182Y+033965X0198Y0197R270 S1      
327P3V3_HPDB_FB     PC54  -1          A01X+177982Y+033965X0198Y0197R270 S1      
327P3V3_HPDB_FB     PR112 -1   M      A01X+177582Y+033965X0198Y0197R270 S1      
317m0111            VIA   -    MD0100PA00X+177298Y+012450X0200Y         S0      
327m0111            R20   -1   M      A01X+177058Y+012450X0198Y0197R180 S1      
327m0111            R63   -2          A01X+177068Y+012050X0198Y0197     S1      
327m0111            R4    -2          A01X+171200Y+016042X0198Y0197R270 S1      
317m0111            VIA   -    M      A01X+170960Y+015800X0200Y         S2      
017m0111            VIA   -    M      A10X+170960Y+015800X0260Y         S2      
017m0111                  -    MD0100PA00X+170960Y+015800                       
327m0111            R389  -1   M      A01X+170720Y+016042X0198Y0197R090 S1      
327m0112            U26   -D          A01X+173500Y+019594X0320Y0360     S1      
327m0112            VIA   -    M      A01X+174450Y+018750X0300Y         S1      
327m0112            R386  -1   M      A01X+173508Y+020150X0198Y0197R180 S1      
327m0112            U21   -1          A01X+173768Y+018124X0180Y0520R270 S1      
317m0113            VIA   -    MD0100PA00X+071740Y+033000X0200Y         S0      
317m0113            JP6   -2    D0460PA00X+082590Y+037220X0660Y    R090 S3      
327m0113            R384  -2          A01X+069676Y+017800X0440Y0540     S1      
327m0113            U23   -D   M      A01X+069004Y+018800X0320Y0360R270 S1      
327m0113            R385  -1   M      A01X+069158Y+017850X0198Y0197R180 S1      
327m0113            U25   -G   M      A01X+069716Y+019724X0320Y0360R270 S1      
327m0114            R154  -2   M      A01X+103184Y+019050X0440Y0540R180 S1      
317m0114            VIA   -    MD0100PA00X+103454Y+020144X0200Y         S0      
327m0114            U22   -D          A01X+104710Y+018956X0320Y0360R180 S1      
327m0114            R155  -1   M      A01X+103760Y+018892X0198Y0197R090 S1      
327m0114            U24   -G   M      A01X+103694Y+019776X0320Y0360R090 S1      
317m0114            JP5   -2    D0460PA00X+090690Y+037220X0660Y    R090 S3      
317m0114            VIA   -    M      A01X+102141Y+035598X0200Y         S2      
017m0114            VIA   -    M      A10X+102141Y+035598X0260Y         S2      
017m0114                  -    MD0100PA00X+102141Y+035598                       
327m0115            VIA   -    M      A01X+175500Y+017400X0300Y         S1      
327m0115            U21   -4          A01X+174732Y+017376X0180Y0520R270 S1      
327m0115            R382  -1          A01X+175992Y+017400X0198Y0197     S1      
317GPU_HSC_EN       J11   -S14  D0410PA00X+184896Y+032421X0610Y    R090 S3      
317GPU_HSC_EN       VIA   -    MD0100PA00X+172848Y+017500X0200Y         S0      
327GPU_HSC_EN       U21   -2          A01X+173768Y+017750X0180Y0520R270 S1      
327GPU_HSC_EN       R381  -1   M      A01X+172608Y+017500X0198Y0197R180 S1      
327GPU_HSC_EN       R383  -2   M      A01X+172608Y+017950X0198Y0197     S1      
317GPU_HSC_EN       VIA   -    M      A01X+180960Y+019500X0300Y         S1      
017GPU_HSC_EN       VIA   -    M      A10X+180960Y+019500X0200Y         S1      
017GPU_HSC_EN             -    MD0100PA00X+180960Y+019500                       
327m0116            U25   -D          A01X+070504Y+019350X0320Y0360R270 S1      
317m0116            VIA   -    M      A01X+070222Y+019742X0200Y    R180 S2      
017m0116            VIA   -    M      A10X+070222Y+019742X0260Y    R180 S2      
017m0116                  -    MD0100PA00X+070222Y+019742                       
327m0116            R5896 -1          A10X+070742Y+021200X0198Y0197R180 S2      
327m0117            U24   -D          A01X+102906Y+020150X0320Y0360R090 S1      
317m0117            VIA   -    M      A01X+102768Y+021500X0300Y         S1      
017m0117            VIA   -    M      A10X+102768Y+021500X0200Y         S1      
017m0117                  -    MD0100PA00X+102768Y+021500                       
327m0117            R413  -1          A10X+102768Y+021250X0198Y0197     S2      
327m0118            R5898 -2          A01X+170750Y+019542X0198Y0197R270 S1      
317m0118            J11   -S4   D0410PA00X+185396Y+032921X0610Y    R090 S3      
317m0118            VIA   -    MD0100PA00X+172150Y+020500X0200Y         S0      
317m0118            VIA   -    M      A01X+181750Y+018800X0200Y         S2      
017m0118            VIA   -    M      A10X+181750Y+018800X0260Y         S2      
017m0118                  -    MD0100PA00X+181750Y+018800                       
327BOARD_ID_1       VIA   -    M      A01X+167360Y+015850X0300Y         S1      
327BOARD_ID_1       R134  -2          A01X+169242Y+015350X0198Y0197R180 S1      
327BOARD_ID_1       U8    -16         A01X+166650Y+016060X0140Y0590R270 S1      
327BOARD_ID_1       R137  -1   M      A01X+168042Y+015350X0198Y0197     S1      
317BOARD_ID_2       VIA   -    M      A01X+167635Y+016025X0200Y         S2      
017BOARD_ID_2       VIA   -    M      A10X+167635Y+016025X0260Y         S2      
017BOARD_ID_2             -    MD0100PA00X+167635Y+016025                       
327BOARD_ID_2       R133  -2          A01X+169242Y+015900X0198Y0197R180 S1      
327BOARD_ID_2       U8    -17         A01X+166650Y+016316X0140Y0590R270 S1      
327BOARD_ID_2       R136  -1   M      A01X+168042Y+015900X0198Y0197     S1      
317BOARD_ID_0       VIA   -    M      A01X+168810Y+014556X0200Y         S2      
017BOARD_ID_0       VIA   -    M      A10X+168810Y+014556X0260Y         S2      
017BOARD_ID_0             -    MD0100PA00X+168810Y+014556                       
327BOARD_ID_0       R135  -2          A01X+169242Y+014800X0198Y0197R180 S1      
327BOARD_ID_0       U8    -15         A01X+166650Y+015804X0140Y0590R270 S1      
327BOARD_ID_0       R138  -1   M      A01X+168042Y+014800X0198Y0197     S1      
327TP_P52V_HS2_EN   VIA   -           A01X+080940Y+036220X0300Y         S1      
317TP_P52V_HS2_EN   JP6   -1    D0460PA00X+082590Y+036220X0660Y0660R090 S3      
327TP_P52V_HS1_EN   VIA   -           A01X+092310Y+036220X0300Y         S1      
317TP_P52V_HS1_EN   JP5   -1    D0460PA00X+090690Y+036220X0660Y0660R090 S3      
327m0119            PR99  -2          A01X+152508Y+011450X0198Y0197     S1      
317m0119            VIA   -    MD0100PA00X+152460Y+011150X0200Y         S0      
327m0119            PR100 -1          A01X+157487Y+008500X0630Y1380     S1      
327m0119            PR101 -1          A01X+157487Y+006700X0630Y1380     S1      
327m0119            PQ15  -S          A01X+157550Y+010425X0520Y1220     S1      
317m0119            VIA   -    M      A01X+156750Y+006700X0200Y         S2      
017m0119            VIA   -    M      A10X+156750Y+006700X0260Y         S2      
017m0119                  -    MD0100PA00X+156750Y+006700                       
327m0120            VIA   -    M      A01X+152460Y+011950X0300Y         S1      
327m0120            PQ17  -B          A01X+153110Y+011650X0400Y0500R270 S1      
327m0120            PR99  -1          A01X+152192Y+011450X0198Y0197     S1      
317m0121            VIA   -    M      A01X+155100Y+009650X0200Y         S2      
017m0121            VIA   -    M      A10X+155100Y+009650X0260Y         S2      
017m0121                  -    MD0100PA00X+155100Y+009650                       
327m0121            PR98  -2          A01X+153960Y+012370X0400Y0630R270 S1      
327m0121            PQ17  -C   M      A01X+153990Y+011250X0400Y0500R270 S1      
327m0121            PU3   -D   M      A01X+154115Y+009950X0240Y0320R270 S1      
327m0121            PQ15  -G          A01X+155550Y+010425X0520Y1220     S1      
327m0122            PU3   -G          A01X+153485Y+010206X0240Y0320R270 S1      
327m0122            VIA   -    M      A01X+152940Y+010208X0300Y         S1      
327m0122            PR102 -2          A01X+152450Y+010208X0198Y0197R090 S1      
327m0123            VIA   -           A01X+176050Y+011950X0300Y         S1      
327m0123            U18   -11         A01X+175290Y+011950X0220Y0680R270 S1      
327PU_9543_1_FAN    VIA   -    M      A01X+176110Y+010450X0300Y         S1      
327PU_9543_1_FAN    R16   -1          A01X+176742Y+010450X0198Y0197     S1      
327PU_9543_1_FAN    U18   -8          A01X+175290Y+010450X0220Y0680R270 S1      
327PU_9543_0_FAN    VIA   -    M      A01X+172460Y+011950X0300Y         S1      
327PU_9543_0_FAN    U18   -4          A01X+173210Y+011950X0220Y0680R270 S1      
327PU_9543_0_FAN    R15   -1          A01X+171908Y+011950X0198Y0197R180 S1      
317SKU_ID_0         VIA   -    M      A01X+168810Y+016206X0200Y         S2      
017SKU_ID_0         VIA   -    M      A10X+168810Y+016206X0260Y         S2      
017SKU_ID_0               -    MD0100PA00X+168810Y+016206                       
327SKU_ID_0         R98   -2          A01X+169242Y+016450X0198Y0197R180 S1      
327SKU_ID_0         U8    -18         A01X+166650Y+016572X0140Y0590R270 S1      
327SKU_ID_0         R101  -1   M      A01X+168042Y+016450X0198Y0197     S1      
317SKU_ID_2         VIA   -    M      A01X+168810Y+017306X0200Y         S2      
017SKU_ID_2         VIA   -    M      A10X+168810Y+017306X0260Y         S2      
017SKU_ID_2               -    MD0100PA00X+168810Y+017306                       
327SKU_ID_2         R96   -2          A01X+169242Y+017550X0198Y0197R180 S1      
327SKU_ID_2         R99   -1   M      A01X+168042Y+017550X0198Y0197     S1      
327SKU_ID_2         U8    -20         A01X+166650Y+017084X0140Y0590R270 S1      
327SKU_ID_1         VIA   -    M      A01X+167410Y+016828X0300Y         S1      
327SKU_ID_1         R97   -2          A01X+169242Y+017000X0198Y0197R180 S1      
327SKU_ID_1         R100  -1   M      A01X+168042Y+017000X0198Y0197     S1      
327SKU_ID_1         U8    -19         A01X+166650Y+016828X0140Y0590R270 S1      
317NC_J7_D1         VIA   -     D0100PA00X+077600Y+020660X0200Y         S2      
317NC_J7_D1         J7    -D1   D0402PA00X+079209Y+020098X0602Y    R180 S3      
317NC_J7_C1         VIA   -     D0100PA00X+077070Y+020690X0200Y         S2      
317NC_J7_C1         J7    -C1   D0402PA00X+080209Y+020098X0602Y    R180 S3      
317NC_J6_D1         VIA   -     D0100PA00X+095460Y+020720X0200Y         S2      
317NC_J6_D1         J6    -D1   D0402PA00X+091020Y+020098X0602Y    R180 S3      
317NC_J6_C1         VIA   -     D0100PA00X+095420Y+020020X0200Y         S2      
317NC_J6_C1         J6    -C1   D0402PA00X+092020Y+020098X0602Y    R180 S3      
327NC_U2_READY      VIA   -           A01X+175900Y+014000X0300Y         S1      
327NC_U2_READY      U2    -5          A01X+175129Y+014366X0140Y0560R270 S1      
327NC_U1_READY      VIA   -           A01X+175900Y+015600X0300Y         S1      
327NC_U1_READY      U1    -5          A01X+175129Y+015916X0140Y0560R270 S1      
327m0124            PR105 -2          A01X+020800Y+011858X0198Y0197R090 S1      
317m0124            VIA   -    M      A01X+021092Y+011558X0200Y         S2      
017m0124            VIA   -    M      A10X+021092Y+011558X0260Y         S2      
017m0124                  -    MD0100PA00X+021092Y+011558                       
327m0124            PR106 -1          A01X+017643Y+009100X0630Y1380     S1      
327m0124            PR107 -1          A01X+017643Y+007300X0630Y1380     S1      
317m0124            VIA   -    MD0100PA00X+017678Y+010200X0200Y         S0      
327m0124            PQ16  -S          A01X+017678Y+011025X0520Y1220     S1      
327m0125            VIA   -    M      A01X+020292Y+010292X0300Y         S1      
327m0125            PR103 -2          A01X+020800Y+010292X0198Y0197R270 S1      
327m0125            PU4   -G          A01X+019725Y+010394X0240Y0320R090 S1      
327m0126            PR104 -2          A01X+019260Y+013020X0400Y0630R270 S1      
317m0126            VIA   -    MD0100PA00X+018760Y+010650X0200Y         S0      
327m0126            PU4   -D   M      A01X+019095Y+010650X0240Y0320R090 S1      
327m0126            PQ18  -C   M      A01X+019188Y+011900X0400Y0500R090 S1      
317m0126            VIA   -    M      A01X+015678Y+010128X0200Y         S2      
017m0126            VIA   -    M      A10X+015678Y+010128X0260Y         S2      
017m0126                  -    MD0100PA00X+015678Y+010128                       
327m0126            PQ16  -G          A01X+015678Y+011025X0520Y1220     S1      
327m0127            VIA   -    M      A01X+020690Y+011070X0300Y         S1      
327m0127            PQ18  -B          A01X+020068Y+011500X0400Y0500R090 S1      
327m0127            PR105 -1          A01X+020800Y+011542X0198Y0197R090 S1      
327TP_U8_P06        U8    -10         A01X+164350Y+015804X0140Y0590R270 S1      
317TP_U8_P06        VIA   -           A01X+165750Y+019150X0300Y         S1      
017TP_U8_P06        VIA   -           A10X+165750Y+019150X0200Y         S1      
017TP_U8_P06              -     D0100PA00X+165750Y+019150                       
317TP_U8_P04        VIA   -           A01X+165012Y+018000X0200Y         S2      
017TP_U8_P04        VIA   -           A10X+165012Y+018000X0260Y         S2      
017TP_U8_P04              -     D0100PA00X+165012Y+018000                       
327TP_U8_P04        U8    -8          A01X+164350Y+016316X0140Y0590R270 S1      
327P52V_HS1_OV      PU1   -12         A10X+115658Y+026261X0110Y0300     S2      
327P52V_HS1_OV      VIA   -    M      A10X+107730Y+029400X0260Y         S2      
327P52V_HS1_OV      PR480 -2          A10X+108060Y+032776X0440Y0540R270 S2      
317P52V_HS1_OV      VIA   -    MD0100PA00X+108060Y+032400X0200Y         S0      
317P52V_HS1_OV      VIA   -    MD0100PA00X+108060Y+029400X0200Y         S0      
327P52V_HS1_OV      PC575 -1          A10X+108610Y+029942X0198Y0197R270 S2      
327P52V_HS1_OV      PR482 -1   M      A10X+108210Y+029942X0198Y0197R270 S2      
327P52V_HS1_OV      PU7   -47         A10X+107443Y+028758X0120Y0330     S2      
317P52V_HS1_OV      VIA   -    MD0100PA00X+116099Y+025213X0200Y         S0      
317m0128            J8    -S8   D0295PA00X+146520Y+001801X0455Y    R270 S3      
317m0128            VIA   -    M      A01X+149023Y+006650X0200Y         S2      
017m0128            VIA   -    M      A10X+149023Y+006650X0260Y         S2      
017m0128                  -    MD0100PA00X+149023Y+006650                       
327m0128            R73   -2          A01X+149023Y+006893X0198Y0197R270 S1      
327m0129            VIA   -    M      A10X+149400Y+005950X0260Y         S2      
317m0129            J8    -S7   D0295PA00X+147020Y+002301X0455Y    R270 S3      
317m0129            VIA   -    MD0100PA00X+149473Y+006650X0200Y         S0      
327m0129            R71   -2          A01X+149473Y+006893X0198Y0197R270 S1      
327PU_U8_PIN1       VIA   -    M      A01X+163420Y+018050X0300Y         S1      
327PU_U8_PIN1       U8    -1          A01X+164350Y+018108X0140Y0590R270 S1      
327PU_U8_PIN1       R48   -2          A01X+162958Y+018300X0198Y0197     S1      
327FAN_PWR_EN_BUF   R5940 -1          A10X+173592Y+018100X0198Y0197R180 S2      
317FAN_PWR_EN_BUF   J11   -S12  D0410PA00X+184896Y+033421X0610Y    R090 S3      
317FAN_PWR_EN_BUF   VIA   -    M      A01X+177350Y+012950X0200Y         S2      
017FAN_PWR_EN_BUF   VIA   -    M      A10X+177350Y+012950X0260Y         S2      
017FAN_PWR_EN_BUF         -    MD0100PA00X+177350Y+012950                       
317FAN_PWR_EN_BUF   VIA   -    MD0100PA00X+150373Y+007448X0200Y         S0      
327FAN_PWR_EN_BUF   R72   -2          A01X+150373Y+007208X0198Y0197R090 S1      
327FAN_PWR_EN_BUF   R76   -2          A01X+032600Y+007208X0198Y0197R090 S1      
317FAN_PWR_EN_BUF   VIA   -    MD0100PA00X+032600Y+007448X0200Y         S0      
327P52V_2_BUSBAR    VIA   -    M      A10X+078810Y+038300X0260Y         S2      
317P52V_2_BUSBAR    J7    -A1   D0402PA00X+082209Y+020098X0602Y0602R180 S3      
317P52V_2_BUSBAR    VIA   -    MD0100PA00X+062350Y+037900X0200Y    R180 S0      
317P52V_2_BUSBAR    VIA   -    MD0100PA00X+063219Y+033892X0200Y    R270 S0      
327P52V_2_BUSBAR    R5906 -1          A01X+063100Y+032124X0440Y0540R090 S1      
317FAN_PWR_EN_0_R   J8    -S2   D0295PA00X+147020Y+001301X0455Y    R270 S3      
317FAN_PWR_EN_0_R   VIA   -    M      A01X+150510Y+006450X0200Y         S2      
017FAN_PWR_EN_0_R   VIA   -    M      A10X+150510Y+006450X0260Y         S2      
017FAN_PWR_EN_0_R         -    MD0100PA00X+150510Y+006450                       
327FAN_PWR_EN_0_R   R72   -1          A01X+150373Y+006893X0198Y0197R090 S1      
327P52V_1_BUSBAR    VIA   -    M      A10X+104140Y+036860X0260Y         S2      
317P52V_1_BUSBAR    J6    -A1   D0402PA00X+094020Y+020098X0602Y0602R180 S3      
327P52V_1_BUSBAR    R5902 -1          A10X+107426Y+036050X0440Y0540     S2      
327PCA9555_A0       VIA   -    M      A01X+167460Y+017600X0300Y         S1      
327PCA9555_A0       R53   -2          A01X+169242Y+018100X0198Y0197R180 S1      
327PCA9555_A0       R56   -1   M      A01X+168042Y+018100X0198Y0197     S1      
327PCA9555_A0       U8    -21         A01X+166650Y+017340X0140Y0590R270 S1      
327PCA9555_A1       VIA   -    M      A01X+162000Y+017750X0300Y         S1      
327PCA9555_A1       R52   -2          A01X+161850Y+018242X0198Y0197R270 S1      
327PCA9555_A1       U8    -2          A01X+164350Y+017852X0140Y0590R270 S1      
327PCA9555_A1       R55   -1   M      A01X+162958Y+017800X0198Y0197R180 S1      
327SMB_FRU_CLK      R63   -1          A01X+176752Y+012050X0198Y0197     S1      
317SMB_FRU_CLK      VIA   -    MD0100PA00X+176410Y+011950X0200Y         S0      
317SMB_FRU_CLK      VIA   -    M      A01X+169660Y+011900X0200Y    R090 S2      
017SMB_FRU_CLK      VIA   -    M      A10X+169660Y+011900X0260Y    R090 S2      
017SMB_FRU_CLK            -    MD0100PA00X+169660Y+011900                       
327SMB_FRU_CLK      U9    -6          A01X+170110Y+010730X0220Y0680     S1      
327m0130            VIA   -    M      A01X+164892Y+019400X0300Y         S1      
327m0130            U29   -D          A01X+164304Y+019100X0320Y0360R270 S1      
327m0130            R419  -1          A01X+165242Y+019900X0198Y0197     S1      
327PCA9555_A2       VIA   -    M      A01X+162050Y+017050X0300Y         S1      
327PCA9555_A2       R51   -2          A01X+161558Y+017300X0198Y0197     S1      
327PCA9555_A2       R54   -1   M      A01X+162958Y+017250X0198Y0197R180 S1      
327PCA9555_A2       U8    -3          A01X+164350Y+017596X0140Y0590R270 S1      
327P52V_1           R5901 -1          A10X+111300Y+034576X0440Y0540R090 S2      
327P52V_1           PR481 -1          A10X+106460Y+033524X0440Y0540R270 S2      
327P52V_1           PR4   -1          A10X+107260Y+033524X0440Y0540R270 S2      
327P52V_1           PR480 -1          A10X+108060Y+033524X0440Y0540R270 S2      
327P52V_1           PR18  -1   M      A10X+108810Y+033524X0440Y0540R270 S2      
317P52V_1           VIA   -    MD0100PA00X+108930Y+033950X0200Y         S0      
317P52V_1           VIA   -    MD0100PA00X+108680Y+033950X0200Y         S0      
317P52V_1           VIA   -    MD0100PA00X+107930Y+033950X0200Y         S0      
317P52V_1           VIA   -    MD0100PA00X+108180Y+033950X0200Y         S0      
317P52V_1           VIA   -    MD0100PA00X+107130Y+033950X0200Y         S0      
317P52V_1           VIA   -    MD0100PA00X+107380Y+033950X0200Y         S0      
317P52V_1           VIA   -    MD0100PA00X+106330Y+033950X0200Y         S0      
317P52V_1           VIA   -    MD0100PA00X+106580Y+033950X0200Y         S0      
327P52V_1           VIA   -    M      A10X+111300Y+033900X0260Y         S2      
327P52V_1           VIA   -           A10X+105050Y+033650X0260Y         S2      
327P52V_1           PR5   -1          A10X+103660Y+031330X0400Y0630R090 S2      
327P52V_1           PU1   -10         A10X+116643Y+026251X0110Y0280     S2      
327P52V_1           PR479 -1A         A01X+119042Y+024950X1260Y2700R180 S1      
317P52V_1           VIA   -    MD0100PA00X+118210Y+023900X0200Y         S0      
317P52V_1           VIA   -    MD0100PA00X+118210Y+024200X0200Y         S0      
317P52V_1           VIA   -    MD0100PA00X+118210Y+026000X0200Y         S0      
317P52V_1           VIA   -    MD0100PA00X+118210Y+025700X0200Y         S0      
317P52V_1           VIA   -    MD0100PA00X+118210Y+024500X0200Y         S0      
317P52V_1           VIA   -    MD0100PA00X+118210Y+024800X0200Y         S0      
317P52V_1           VIA   -    MD0100PA00X+118210Y+025100X0200Y         S0      
317P52V_1           VIA   -    MD0100PA00X+118210Y+025400X0200Y         S0      
317P52V_1           VIA   -    MD0100PA00X+117910Y+025400X0200Y         S0      
317P52V_1           VIA   -    MD0100PA00X+117910Y+025100X0200Y         S0      
317P52V_1           VIA   -    MD0100PA00X+117910Y+024800X0200Y         S0      
317P52V_1           VIA   -    MD0100PA00X+117910Y+024500X0200Y         S0      
317P52V_1           VIA   -    MD0100PA00X+117910Y+025700X0200Y         S0      
317P52V_1           VIA   -    MD0100PA00X+117910Y+026000X0200Y         S0      
317P52V_1           VIA   -    MD0100PA00X+117910Y+024200X0200Y         S0      
317P52V_1           VIA   -    MD0100PA00X+117910Y+023900X0200Y         S0      
317P52V_1           VIA   -    M      A01X+117160Y+023800X0300Y         S1      
017P52V_1           VIA   -    M      A10X+117160Y+023800X0200Y         S1      
017P52V_1                 -    MD0100PA00X+117160Y+023800                       
317P52V_1           VIA   -    MD0100PA00X+117160Y+024150X0200Y         S0      
327P52V_1           PC3   -1          A10X+116740Y+023950X0460Y0620R180 S2      
317P52V_1           VIA   -    MD0100PA00X+117610Y+023900X0200Y         S0      
317P52V_1           VIA   -    MD0100PA00X+117610Y+024200X0200Y         S0      
317P52V_1           VIA   -    MD0100PA00X+117610Y+026000X0200Y         S0      
317P52V_1           VIA   -    MD0100PA00X+117610Y+025700X0200Y         S0      
317P52V_1           VIA   -    MD0100PA00X+117610Y+024500X0200Y         S0      
317P52V_1           VIA   -    MD0100PA00X+117610Y+024800X0200Y         S0      
317P52V_1           VIA   -    MD0100PA00X+117610Y+025100X0200Y         S0      
317P52V_1           VIA   -    MD0100PA00X+117610Y+025400X0200Y         S0      
317P52V_1           VIA   -    MD0100PA00X+117910Y+012680X0200Y         S0      
317P52V_1           VIA   -    MD0100PA00X+117910Y+012380X0200Y         S0      
317P52V_1           VIA   -    MD0100PA00X+117910Y+011180X0200Y         S0      
317P52V_1           VIA   -    MD0100PA00X+117910Y+011480X0200Y         S0      
317P52V_1           VIA   -    MD0100PA00X+117910Y+011780X0200Y         S0      
317P52V_1           VIA   -    MD0100PA00X+117910Y+012080X0200Y         S0      
317P52V_1           VIA   -    MD0100PA00X+118210Y+012080X0200Y         S0      
317P52V_1           VIA   -    MD0100PA00X+118210Y+011780X0200Y         S0      
317P52V_1           VIA   -    MD0100PA00X+118210Y+011480X0200Y         S0      
317P52V_1           VIA   -    MD0100PA00X+118210Y+011180X0200Y         S0      
317P52V_1           VIA   -    MD0100PA00X+118210Y+012380X0200Y         S0      
317P52V_1           VIA   -    MD0100PA00X+118210Y+012680X0200Y         S0      
317P52V_1           VIA   -    MD0100PA00X+117610Y+012080X0200Y         S0      
317P52V_1           VIA   -    MD0100PA00X+117610Y+011780X0200Y         S0      
317P52V_1           VIA   -    MD0100PA00X+117610Y+011480X0200Y         S0      
317P52V_1           VIA   -    MD0100PA00X+117610Y+011180X0200Y         S0      
317P52V_1           VIA   -    MD0100PA00X+117610Y+012380X0200Y         S0      
317P52V_1           VIA   -    MD0100PA00X+117610Y+012680X0200Y         S0      
327P52V_1           PR315 -1A         A01X+119042Y+011630X1260Y2700R180 S1      
317P52V_1           VIA   -    MD0100PA00X+117910Y+010580X0200Y         S0      
317P52V_1           VIA   -    MD0100PA00X+117910Y+010880X0200Y         S0      
317P52V_1           VIA   -    MD0100PA00X+118210Y+010880X0200Y         S0      
317P52V_1           VIA   -    M      A01X+118210Y+010580X0200Y         S2      
017P52V_1           VIA   -    M      A10X+118210Y+010580X0260Y         S2      
017P52V_1                 -    MD0100PA00X+118210Y+010580                       
317P52V_1           VIA   -    MD0100PA00X+117610Y+010880X0200Y         S0      
317P52V_1           VIA   -    MD0100PA00X+117610Y+010580X0200Y         S0      
327P52V_1           FS5   -2          A10X+099400Y+014009X1280Y1350R090 S2      
317P52V_1           VIA   -    MD0100PA00X+099695Y+013106X0200Y         S0      
317P52V_1           VIA   -    M      A01X+099695Y+012806X0300Y         S1      
017P52V_1           VIA   -    M      A10X+099695Y+012806X0200Y         S1      
017P52V_1                 -    MD0100PA00X+099695Y+012806                       
317P52V_1           VIA   -    MD0100PA00X+099395Y+012806X0200Y         S0      
317P52V_1           VIA   -    MD0100PA00X+099395Y+013106X0200Y         S0      
317P52V_1           VIA   -    MD0100PA00X+099095Y+012806X0200Y         S0      
317P52V_1           VIA   -    MD0100PA00X+099095Y+013106X0200Y         S0      
317P52V_1           J6    -P2_2MD0402PA00X+092020Y+017098X0602Y    R180 S3      
317P52V_1           J6    -P2_3MD0402PA00X+093020Y+017098X0602Y    R180 S3      
317P52V_1           J6    -P2_4MD0402PA00X+094020Y+017098X0602Y    R180 S3      
317P52V_1           J6    -P2_6MD0402PA00X+092020Y+018098X0602Y    R180 S3      
317P52V_1           J6    -P2_7MD0402PA00X+093020Y+018098X0602Y    R180 S3      
317P52V_1           J6    -P2_8MD0402PA00X+094020Y+018098X0602Y    R180 S3      
317P52V_1           J6    -P2_1MD0402PA00X+091020Y+017098X0602Y    R180 S3      
317P52V_1           J6    -P2_5MD0402PA00X+091020Y+018098X0602Y    R180 S3      
317P52V_1           J6    -P1_2MD0402PA00X+092020Y+013598X0602Y    R180 S3      
317P52V_1           J6    -P1_3MD0402PA00X+093020Y+013598X0602Y    R180 S3      
317P52V_1           J6    -P1_4MD0402PA00X+094020Y+013598X0602Y    R180 S3      
317P52V_1           J6    -P1_6MD0402PA00X+092020Y+014598X0602Y    R180 S3      
317P52V_1           J6    -P1_7MD0402PA00X+093020Y+014598X0602Y    R180 S3      
317P52V_1           J6    -P1_8MD0402PA00X+094020Y+014598X0602Y    R180 S3      
317P52V_1           J6    -P1_1MD0402PA00X+091020Y+013598X0602Y    R180 S3      
317P52V_1           J6    -P1_5MD0402PA00X+091020Y+014598X0602Y    R180 S3      
317SMB_FRU_DAT      VIA   -    M      A01X+170135Y+011425X0200Y    R090 S2      
017SMB_FRU_DAT      VIA   -    M      A10X+170135Y+011425X0260Y    R090 S2      
017SMB_FRU_DAT            -    MD0100PA00X+170135Y+011425                       
327SMB_FRU_DAT      R62   -1          A01X+170010Y+012182X0198Y0197R090 S1      
327SMB_FRU_DAT      U9    -5          A01X+170610Y+010730X0220Y0680     S1      
327m0131            VIA   -           A01X+118770Y+028800X0300Y         S1      
327m0131            PR6960-2   M      A01X+118770Y+027550X0280Y0320R090 S1      
317m0131            VIA   -    MD0100PA00X+118770Y+026560X0200Y         S0      
327m0131            PR6963-2   M      A01X+118770Y+026850X0280Y0320R090 S1      
327m0131            PR6956-2   M      A01X+118770Y+028250X0280Y0320R090 S1      
327m0131            PR479 -1B         A01X+119622Y+024950X0100Y0200     S1      
317m0131            VIA   -    MD0100PA00X+119928Y+025168X0200Y         S0      
327m0132            PR6958-2   M      A01X+121050Y+027550X0280Y0320R270 S1      
317m0132            VIA   -    M      A01X+121050Y+026560X0200Y         S2      
017m0132            VIA   -    M      A10X+121050Y+026560X0260Y         S2      
017m0132                  -    MD0100PA00X+121050Y+026560                       
327m0132            PR6962-2   M      A01X+121050Y+026850X0280Y0320R270 S1      
327m0132            PR6957-2          A01X+121050Y+028250X0280Y0320R270 S1      
327m0132            PR479 -2B         A01X+120234Y+024950X0100Y0200     S1      
317m0132            VIA   -    MD0100PA00X+119928Y+024732X0200Y         S0      
327P52V_HS1_VCAP    R372  -1          A01X+109868Y+028750X0198Y0197R180 S1      
327P52V_HS1_VCAP    R371  -1          A01X+109868Y+029150X0198Y0197R180 S1      
317P52V_HS1_VCAP    VIA   -    MD0100PA00X+110160Y+028950X0200Y         S0      
327P52V_HS1_VCAP    PR6933-2          A10X+109918Y+028950X0198Y0197R180 S2      
327P52V_HS1_VCAP    PC591 -1          A10X+109120Y+027800X0280Y0320R270 S2      
317P52V_HS1_VCAP    VIA   -    MD0100PA00X+108710Y+028250X0200Y         S0      
327P52V_HS1_VCAP    PR6934-2          A10X+109052Y+028300X0198Y0197     S2      
327P52V_HS1_VCAP    PU7   -3          A10X+107915Y+028089X0120Y0330R090 S2      
317P52V_HS1_EN      VIA   -    MD0100PA00X+113200Y+036700X0200Y    R180 S0      
327P52V_HS1_EN      U34   -4          A10X+112822Y+036624X0220Y0320R270 S2      
327P52V_HS1_EN      PU1   -23         A10X+114221Y+027305X0110Y0300R090 S2      
317P52V_HS1_EN      VIA   -    MD0100PA00X+112980Y+026540X0200Y         S0      
317P52V_HS1_EN      VIA   -    MD0100PA00X+108808Y+027498X0200Y         S0      
327P52V_HS1_EN      PU7   -6          A10X+107915Y+027498X0120Y0330R090 S2      
317P52V_HS1_EN      VIA   -    MD0100PA00X+089450Y+039650X0200Y         S0      
317P52V_HS1_EN      VIA   -    M      A01X+101730Y+038560X0200Y         S2      
017P52V_HS1_EN      VIA   -    M      A10X+101730Y+038560X0260Y         S2      
017P52V_HS1_EN            -    MD0100PA00X+101730Y+038560                       
317P52V_HS1_EN      VIA   -    MD0100PA00X+101730Y+032250X0200Y         S0      
317P52V_HS1_EN      VIA   -    MD0100PA00X+087253Y+002943X0200Y         S0      
317P52V_HS1_EN      VIA   -    MD0100PA00X+152710Y+009892X0200Y         S0      
327P52V_HS1_EN      PR102 -1          A01X+152450Y+009892X0198Y0197R090 S1      
327P52V_HS1_ADR0    PU1   -16         A10X+114871Y+026261X0110Y0300     S2      
327P52V_HS1_ADR0    VIA   -    M      A01X+109180Y+027910X0300Y         S1      
317P52V_HS1_ADR0    VIA   -    MD0100PA00X+110502Y+028900X0200Y         S0      
327P52V_HS1_ADR0    R373  -1   M      A01X+110502Y+029150X0198Y0197     S1      
327P52V_HS1_ADR0    R371  -2   M      A01X+109552Y+029150X0198Y0197R180 S1      
317P52V_HS1_ADR0    VIA   -    MD0100PA00X+108310Y+027302X0200Y         S0      
327P52V_HS1_ADR0    PU7   -7          A10X+107915Y+027302X0120Y0330R090 S2      
317P52V_HS1_ADR0    VIA   -    MD0100PA00X+114960Y+025500X0200Y         S0      
327P52V_HS1_ADR0    R158  -1          A10X+114960Y+024108X0198Y0197R090 S2      
327P52V_HS1_ADR0    R156  -2   M      A10X+114960Y+024958X0198Y0197R270 S2      
327GND              PD7   -A          A10X+100700Y+022099X0950Y1300R270 S2      
327GND              PD9   -A          A10X+098050Y+022099X0950Y1300R270 S2      
327GND              PC59  -2          A01X+177260Y+036300X0400Y0500R180 S1      
327GND              PC58  -2          A01X+177260Y+037000X0400Y0500R180 S1      
327GND              PC618 -2          A01X+175139Y+037323X0400Y0500     S1      
327GND              PC617 -2          A01X+175139Y+036553X0400Y0500     S1      
327GND              PC138 -2          A01X+173287Y+039250X0630Y1380R090 S1      
327GND              PU5   -11_1       A01X+175259Y+033674X0315Y1240R180 S1      
327GND              PC55  -2          A01X+174610Y+033160X0198Y0197R090 S1      
327GND              PC57  -2          A01X+175139Y+035013X0400Y0500     S1      
327GND              PC56  -2          A01X+175139Y+035783X0400Y0500     S1      
327GND              C93   -2          A01X+068050Y+033508X0198Y0197R090 S1      
327GND              R5907 -2          A01X+067650Y+033508X0198Y0197R090 S1      
327GND              PC48  -2          A01X+177960Y+024150X0400Y0500R090 S1      
327GND              PC51  -2          A01X+178660Y+024342X0198Y0197R270 S1      
327GND              PC49  -2          A01X+177110Y+024150X0400Y0500R090 S1      
327GND              PC50  -2          A01X+176210Y+024150X0400Y0500R090 S1      
327GND              D6    -C          A01X+173100Y+024163X0240Y0280R270 S1      
327GND              PC137 -2          A01X+174610Y+023584X0630Y1190     S1      
327GND              R65   -1          A01X+172728Y+009350X0198Y0197R180 S1      
327GND              R66   -1          A01X+172728Y+009900X0198Y0197R180 S1      
327GND              D4    -A          A01X+167300Y+009535X0850Y0890R090 S1      
327GND              PD8   -A          A01X+150160Y+010961X0990Y1300R270 S1      
327GND              PD10  -A          A01X+023068Y+011561X0990Y1300R270 S1      
327GND              R64   -1          A01X+172728Y+008800X0198Y0197R180 S1      
327GND              U9    -4          A01X+170610Y+008650X0220Y0680     S1      
327GND              D5    -A          A01X+162543Y+007980X0670Y0990R090 S1      
327GND              PR100 -2          A01X+159613Y+008500X0630Y1380     S1      
327GND              PR101 -2          A01X+159613Y+006700X0630Y1380     S1      
327GND              R163  -2          A01X+039200Y+004372X0198Y0197R270 S1      
327GND              PC60  -2          A01X+176245Y+032290X0180Y0200R180 S1      
327GND              PD11  -A          A10X+075260Y+022099X0950Y1300R270 S2      
327GND              PD12  -A          A10X+072610Y+022099X0950Y1300R270 S2      
317GND              VIA   -    MD0100PA00X+148292Y+010777X0200Y    R270 S0      
317GND              VIA   -    MD0100PA00X+148292Y+011077X0200Y    R270 S0      
317GND              VIA   -    MD0100PA00X+148292Y+011377X0200Y    R270 S0      
317GND              VIA   -    MD0100PA00X+148292Y+010477X0200Y    R270 S0      
317GND              VIA   -    MD0100PA00X+148592Y+010777X0200Y    R270 S0      
317GND              VIA   -    MD0100PA00X+148592Y+011077X0200Y    R270 S0      
317GND              VIA   -    MD0100PA00X+148592Y+011377X0200Y    R270 S0      
317GND              VIA   -    MD0100PA00X+148592Y+010477X0200Y    R270 S0      
317GND              VIA   -    MD0100PA00X+148892Y+010777X0200Y    R270 S0      
317GND              VIA   -    MD0100PA00X+148892Y+011077X0200Y    R270 S0      
317GND              VIA   -    MD0100PA00X+148892Y+011377X0200Y    R270 S0      
317GND              VIA   -    MD0100PA00X+148892Y+010477X0200Y    R270 S0      
317GND              VIA   -    MD0100PA00X+149192Y+010477X0200Y    R270 S0      
317GND              VIA   -    MD0100PA00X+149192Y+011377X0200Y    R270 S0      
317GND              VIA   -    MD0100PA00X+149192Y+011077X0200Y    R270 S0      
317GND              VIA   -    MD0100PA00X+149192Y+010777X0200Y    R270 S0      
317GND              VIA   -    MD0100PA00X+023739Y+009230X0200Y    R090 S0      
317GND              VIA   -    MD0100PA00X+023339Y+009230X0200Y    R090 S0      
317GND              VIA   -    MD0100PA00X+022989Y+009230X0200Y    R090 S0      
317GND              VIA   -    MD0100PA00X+022589Y+009230X0200Y    R090 S0      
317GND              VIA   -    MD0100PA00X+023745Y+009578X0200Y    R090 S0      
317GND              VIA   -    MD0100PA00X+023345Y+009578X0200Y    R090 S0      
317GND              VIA   -    MD0100PA00X+022995Y+009578X0200Y    R090 S0      
317GND              VIA   -    MD0100PA00X+022595Y+009578X0200Y    R090 S0      
317GND              VIA   -    MD0100PA00X+023733Y+009950X0200Y    R090 S0      
317GND              VIA   -    MD0100PA00X+023333Y+009950X0200Y    R090 S0      
317GND              VIA   -    MD0100PA00X+022983Y+009950X0200Y    R090 S0      
317GND              VIA   -    MD0100PA00X+022583Y+009950X0200Y    R090 S0      
317GND              VIA   -    MD0100PA00X+023733Y+010341X0200Y    R090 S0      
317GND              VIA   -    MD0100PA00X+023333Y+010341X0200Y    R090 S0      
317GND              VIA   -    MD0100PA00X+022983Y+010341X0200Y    R090 S0      
317GND              VIA   -    MD0100PA00X+022583Y+010341X0200Y    R090 S0      
317GND              VIA   -    MD0100PA00X+070420Y+020657X0200Y         S0      
327GND              C94   -2          A01X+166200Y+010842X0180Y0200R090 S1      
327GND              C96   -2          A01X+165462Y+010238X0180Y0200R180 S1      
327GND              R5937 -2          A10X+162692Y+014950X0198Y0197     S2      
327GND              R5938 -2          A10X+162692Y+013900X0198Y0197     S2      
327GND              C95   -2          A10X+162974Y+009633X0400Y0500R180 S2      
317GND              VIA   -    MD0100PA00X+110150Y+026850X0200Y         S0      
317GND              VIA   -    MD0100PA00X+111850Y+028300X0200Y         S0      
317GND              VIA   -    MD0100PA00X+065900Y+028400X0200Y         S0      
317GND              VIA   -    MD0100PA00X+064100Y+026150X0200Y         S0      
317GND              VIA   -    MD0100PA00X+088050Y+036950X0200Y         S0      
327GND              R385  -2          A01X+068842Y+017850X0198Y0197R180 S1      
317GND              VIA   -    MD0100PA00X+149000Y+008400X0200Y         S0      
317GND              VIA   -    MD0100PA00X+032100Y+006300X0200Y         S0      
317GND              VIA   -    MD0100PA00X+176350Y+011300X0200Y         S0      
317GND              VIA   -    MD0100PA00X+176400Y+010700X0200Y         S0      
317GND              VIA   -    MD0100PA00X+032400Y+007700X0200Y         S0      
317GND              VIA   -    MD0100PA00X+177350Y+012100X0200Y         S0      
317GND              VIA   -    MD0100PA00X+171200Y+015300X0200Y         S0      
317GND              VIA   -    MD0100PA00X+184750Y+043700X0200Y         S0      
317GND              VIA   -    MD0100PA00X+184450Y+041650X0200Y         S0      
317GND              VIA   -    MD0100PA00X+065750Y+032692X0200Y         S0      
327GND              C106  -1          A01X+065350Y+032692X0198Y0197R090 S1      
317GND              VIA   -    MD0100PA00X+073450Y+031058X0200Y         S0      
327GND              C107  -1          A01X+073200Y+031058X0198Y0197R270 S1      
317GND              VIA   -    MD0100PA00X+071950Y+031550X0200Y         S0      
327GND              U45   -3          A01X+072044Y+031274X0170Y0240R180 S1      
317GND              VIA   -    MD0100PA00X+064906Y+031400X0200Y    R270 S0      
327GND              U44   -3          A01X+064906Y+031726X0170Y0240     S1      
317GND              VIA   -    MD0100PA00X+117170Y+034990X0200Y         S0      
327GND              C105  -1          A10X+117050Y+035342X0198Y0197R270 S2      
317GND              VIA   -    MD0100PA00X+117850Y+036874X0200Y         S0      
327GND              U43   -3          A10X+117606Y+036874X0170Y0240R180 S2      
317GND              VIA   -    MD0100PA00X+116558Y+034050X0200Y         S0      
327GND              C104  -1          A10X+116558Y+033800X0198Y0197     S2      
317GND              VIA   -    MD0100PA00X+114700Y+034250X0200Y         S0      
327GND              U42   -3          A10X+115026Y+034306X0170Y0240R270 S2      
317GND              VIA   -    MD0100PA00X+174600Y+019124X0200Y         S0      
327GND              U40   -3          A10X+174938Y+019124X0220Y0320R270 S2      
317GND              VIA   -    MD0100PA00X+177008Y+018150X0200Y         S0      
327GND              C103  -2          A10X+177008Y+018400X0198Y0197R180 S2      
317GND              H37   -1   M      A01X+167323Y+049803X4000Y    R180 S3      
017GND              H37   -1   M      A10X+167323Y+049803X3940Y6700R180 S3      
017GND                    -    MD2520PA00X+167323Y+049803                       
317GND              H36   -1   M      A01X+005906Y+049803X4000Y    R180 S3      
017GND              H36   -1   M      A10X+005906Y+049803X3940Y6700R180 S3      
017GND                    -    MD2520PA00X+005906Y+049803                       
317GND              H19   -1   M      A01X+003228Y+054134X4000Y    R180 S3      
017GND              H19   -1   M      A10X+003228Y+054134X3940Y6700R180 S3      
017GND                    -    MD2520PA00X+003228Y+054134                       
317GND              H20   -1   M      A01X+170000Y+054134X4000Y    R180 S3      
017GND              H20   -1   M      A10X+170000Y+054134X3940Y6700R180 S3      
017GND                    -    MD2520PA00X+170000Y+054134                       
317GND              VIA   -    MD0100PA00X+164950Y+017340X0200Y         S0      
327GND              U39   -12         A10X+164350Y+017340X0140Y0590R270 S2      
317GND              VIA   -    MD0100PA00X+166700Y+013800X0200Y         S0      
327GND              C102  -2          A10X+166418Y+013800X0198Y0197R180 S2      
327GND              R5939 -2          A10X+168108Y+014950X0198Y0197R180 S2      
317GND              VIA   -    MD0100PA00X+166200Y+010600X0200Y         S0      
317GND              VIA   -    MD0100PA00X+165705Y+010238X0200Y    R180 S0      
317GND              VIA   -    MD0100PA00X+165099Y+012203X0200Y         S0      
327GND              U38   -2          A01X+164981Y+011871X0100Y0320R180 S1      
327GND              C97   -2          A01X+164927Y+013052X0198Y0197R090 S1      
327GND              R5923 -2          A01X+164528Y+013058X0198Y0197R090 S1      
327GND              C99   -2          A01X+163877Y+013052X0198Y0197R090 S1      
327GND              C100  -2          A01X+163177Y+013052X0198Y0197R090 S1      
327GND              R5926 -2          A01X+162777Y+013052X0198Y0197R090 S1      
327GND              U38   -7          A01X+163996Y+011871X0100Y0320R180 S1      
317GND              VIA   -    MD0100PA00X+164920Y+013292X0200Y         S0      
317GND              VIA   -    MD0100PA00X+163871Y+013295X0200Y         S0      
317GND              VIA   -    MD0100PA00X+164784Y+012181X0200Y         S0      
327GND              U38   -3          A01X+164784Y+011871X0100Y0320R180 S1      
317GND              VIA   -    MD0100PA00X+162987Y+010424X0200Y         S0      
327GND              C98   -1          A01X+162896Y+010103X0280Y0320R270 S1      
327GND              R5925 -1          A01X+162896Y+010808X0198Y0197R090 S1      
317GND              VIA   -    MD0100PA00X+174724Y+037496X0200Y         S0      
317GND              VIA   -    M      A01X+174724Y+037139X0200Y         S2      
017GND              VIA   -    M      A10X+174724Y+037139X0260Y         S2      
017GND                    -    MD0100PA00X+174724Y+037139                       
317GND              VIA   -    MD0100PA00X+174724Y+036726X0200Y         S0      
317GND              VIA   -    M      A01X+174724Y+036369X0200Y         S2      
017GND              VIA   -    M      A10X+174724Y+036369X0260Y         S2      
017GND                    -    MD0100PA00X+174724Y+036369                       
317GND              VIA   -    MD0100PA00X+176800Y+018726X0200Y         S0      
327GND              U37   -S          A01X+176456Y+018726X0320Y0360R270 S1      
317GND              VIA   -    MD0100PA00X+175426Y+018726X0200Y         S0      
327GND              U36   -S          A01X+175056Y+018726X0320Y0360R270 S1      
317GND              J11   -P13 MD0410PA00X+184614Y+026043X0610Y    R090 S3      
317GND              J11   -P16 MD0410PA00X+184614Y+023043X0610Y    R090 S3      
317GND              J11   -P14 MD0410PA00X+184614Y+025043X0610Y    R090 S3      
317GND              J11   -P15 MD0410PA00X+184614Y+024043X0610Y    R090 S3      
327GND              U30   -S          A01X+163534Y+014906X0320Y0360     S1      
317GND              VIA   -    MD0100PA00X+047195Y+035702X0200Y    R180 S0      
317GND              VIA   -    M      A01X+046595Y+035702X0200Y    R180 S2      
017GND              VIA   -    M      A10X+046595Y+035702X0260Y    R180 S2      
017GND                    -    MD0100PA00X+046595Y+035702                       
317GND              VIA   -    MD0100PA00X+046895Y+035702X0200Y    R180 S0      
317GND              VIA   -    MD0100PA00X+045895Y+035722X0200Y    R180 S0      
317GND              VIA   -    M      A01X+045595Y+035722X0200Y    R180 S2      
017GND              VIA   -    M      A10X+045595Y+035722X0260Y    R180 S2      
017GND                    -    MD0100PA00X+045595Y+035722                       
317GND              VIA   -    MD0100PA00X+127134Y+037978X0200Y         S0      
317GND              VIA   -    MD0100PA00X+126834Y+037978X0200Y         S0      
317GND              VIA   -    MD0100PA00X+126534Y+037978X0200Y         S0      
317GND              VIA   -    MD0100PA00X+124793Y+037965X0200Y         S0      
317GND              VIA   -    MD0100PA00X+125093Y+037965X0200Y         S0      
317GND              VIA   -    MD0100PA00X+125393Y+037965X0200Y         S0      
317GND              VIA   -    MD0100PA00X+131037Y+003848X0200Y         S0      
317GND              VIA   -    MD0100PA00X+130737Y+003848X0200Y         S0      
317GND              VIA   -    MD0100PA00X+131337Y+003848X0200Y         S0      
317GND              VIA   -    MD0100PA00X+131637Y+003848X0200Y         S0      
317GND              VIA   -    MD0100PA00X+116137Y+003898X0200Y         S0      
317GND              VIA   -    MD0100PA00X+115837Y+003898X0200Y         S0      
317GND              VIA   -    MD0100PA00X+115237Y+003898X0200Y         S0      
317GND              VIA   -    MD0100PA00X+115537Y+003898X0200Y         S0      
317GND              VIA   -    MD0100PA00X+127037Y+003848X0200Y         S0      
317GND              VIA   -    MD0100PA00X+126737Y+003848X0200Y         S0      
317GND              VIA   -    MD0100PA00X+126137Y+003848X0200Y         S0      
317GND              VIA   -    MD0100PA00X+126437Y+003848X0200Y         S0      
317GND              VIA   -    M      A01X+122593Y+035915X0200Y         S2      
017GND              VIA   -    M      A10X+122593Y+035915X0260Y         S2      
017GND                    -    MD0100PA00X+122593Y+035915                       
317GND              VIA   -    MD0100PA00X+122593Y+035615X0200Y         S0      
317GND              VIA   -    MD0100PA00X+122893Y+035915X0200Y         S0      
317GND              VIA   -    MD0100PA00X+122893Y+035615X0200Y         S0      
317GND              VIA   -    MD0100PA00X+123193Y+035915X0200Y         S0      
317GND              VIA   -    MD0100PA00X+123193Y+035615X0200Y         S0      
317GND              VIA   -    MD0100PA00X+128911Y+037231X0200Y         S0      
317GND              VIA   -    MD0100PA00X+129211Y+037231X0200Y         S0      
317GND              VIA   -    MD0100PA00X+045595Y+034122X0200Y    R180 S0      
317GND              VIA   -    M      A01X+045895Y+034122X0200Y    R180 S2      
017GND              VIA   -    M      A10X+045895Y+034122X0260Y    R180 S2      
017GND                    -    MD0100PA00X+045895Y+034122                       
317GND              VIA   -    MD0100PA00X+045595Y+033822X0200Y    R180 S0      
317GND              VIA   -    MD0100PA00X+045895Y+033822X0200Y    R180 S0      
317GND              VIA   -    M      A01X+048445Y+034122X0200Y    R180 S2      
017GND              VIA   -    M      A10X+048445Y+034122X0260Y    R180 S2      
017GND                    -    MD0100PA00X+048445Y+034122                       
317GND              VIA   -    MD0100PA00X+048445Y+033822X0200Y    R180 S0      
317GND              VIA   -    MD0100PA00X+047845Y+034122X0200Y    R180 S0      
317GND              VIA   -    MD0100PA00X+048145Y+034122X0200Y    R180 S0      
317GND              VIA   -    MD0100PA00X+047845Y+033822X0200Y    R180 S0      
317GND              VIA   -    MD0100PA00X+048145Y+033822X0200Y    R180 S0      
317GND              VIA   -    MD0100PA00X+048992Y+003746X0200Y         S0      
317GND              VIA   -    MD0100PA00X+049292Y+003746X0200Y         S0      
317GND              VIA   -    MD0100PA00X+049592Y+003746X0200Y         S0      
317GND              VIA   -    MD0100PA00X+049892Y+003746X0200Y         S0      
317GND              VIA   -    MD0100PA00X+113900Y+036650X0200Y         S0      
327GND              C91   -2          A10X+113900Y+036408X0198Y0197R270 S2      
317GND              VIA   -    MD0100PA00X+113500Y+036650X0200Y         S0      
327GND              R5903 -2          A10X+113500Y+036408X0198Y0197R270 S2      
317GND              VIA   -    MD0100PA00X+112200Y+036624X0200Y         S0      
327GND              U34   -3          A10X+111878Y+036624X0220Y0320R270 S2      
317GND              VIA   -    MD0100PA00X+111250Y+036470X0200Y         S0      
327GND              R5904 -2          A10X+111250Y+036208X0198Y0197R270 S2      
317GND              VIA   -    MD0100PA00X+110600Y+036450X0200Y         S0      
327GND              C90   -2          A10X+110700Y+036140X0280Y0320     S2      
317GND              VIA   -    MD0100PA00X+066350Y+031150X0200Y         S0      
327GND              R5908 -2          A01X+066350Y+031442X0198Y0197R270 S1      
317GND              VIA   -    MD0100PA00X+066800Y+031150X0200Y         S0      
327GND              C92   -2          A01X+066800Y+031510X0280Y0320R180 S1      
317GND              VIA   -    MD0100PA00X+067100Y+031576X0200Y         S0      
327GND              U35   -3          A01X+067428Y+031576X0220Y0320R270 S1      
317GND              VIA   -    MD0100PA00X+114350Y+025150X0200Y         S0      
327GND              PC4   -2          A01X+114642Y+025150X0198Y0197R180 S1      
317GND              VIA   -    MD0100PA00X+068890Y+018426X0200Y         S0      
327GND              U23   -S          A01X+068216Y+018426X0320Y0360R270 S1      
327GND              PJ5   -2          A10X+060768Y+023405X0280Y0320R180 S2      
327GND              PC605 -2          A10X+062338Y+023100X0460Y0620R180 S2      
327GND              U32   -4          A10X+061667Y+024684X0150Y0460R270 S2      
317GND              VIA   -    MD0100PA00X+062047Y+024684X0200Y    R180 S0      
317GND              VIA   -    MD0100PA00X+062479Y+023579X0200Y    R090 S0      
317GND              VIA   -    MD0100PA00X+062229Y+023579X0200Y    R090 S0      
317GND              VIA   -    MD0100PA00X+165260Y+021200X0200Y         S0      
327GND              R161  -2          A01X+164100Y+020458X0198Y0197R090 S1      
317GND              VIA   -    MD0100PA00X+060168Y+030558X0200Y         S0      
327GND              PC599 -2          A01X+060142Y+030000X0198Y0197R180 S1      
317GND              VIA   -    MD0100PA00X+075850Y+022850X0200Y         S0      
317GND              VIA   -    MD0100PA00X+074950Y+022850X0200Y         S0      
317GND              VIA   -    MD0100PA00X+075250Y+022850X0200Y         S0      
317GND              VIA   -    MD0100PA00X+075550Y+022850X0200Y         S0      
317GND              VIA   -    MD0100PA00X+074650Y+022850X0200Y         S0      
317GND              VIA   -    MD0100PA00X+072900Y+022850X0200Y         S0      
317GND              VIA   -    MD0100PA00X+072600Y+022850X0200Y         S0      
317GND              VIA   -    MD0100PA00X+072300Y+022850X0200Y         S0      
317GND              VIA   -    MD0100PA00X+072000Y+022850X0200Y         S0      
317GND              VIA   -    MD0100PA00X+073200Y+022850X0200Y         S0      
327GND              U29   -S          A01X+163516Y+018726X0320Y0360R270 S1      
327GND              R5897 -2          A10X+070742Y+020800X0198Y0197     S2      
317GND              VIA   -    MD0100PA00X+069386Y+018976X0200Y         S0      
327GND              C88   -2          A10X+070420Y+020300X0280Y0320R090 S2      
317GND              VIA   -    MD0100PA00X+040810Y+018010X0200Y         S0      
327GND              PC593 -1          A10X+041520Y+018010X0280Y0320R270 S2      
317GND              VIA   -    MD0100PA00X+040810Y+022450X0200Y         S0      
327GND              PC592 -1          A10X+041520Y+022450X0280Y0320R270 S2      
317GND              VIA   -    MD0100PA00X+163158Y+018878X0200Y         S0      
317GND              VIA   -    MD0100PA00X+162310Y+017800X0200Y         S0      
327GND              R55   -2          A01X+162642Y+017800X0198Y0197R180 S1      
317GND              VIA   -    MD0100PA00X+162310Y+017250X0200Y         S0      
327GND              R54   -2          A01X+162642Y+017250X0198Y0197R180 S1      
317GND              VIA   -    MD0100PA00X+171102Y+018700X0200Y         S0      
327GND              C89   -2          A01X+171102Y+018950X0198Y0197R180 S1      
317GND              VIA   -    MD0100PA00X+172482Y+020528X0200Y         S0      
327GND              U33   -3          A01X+172482Y+020224X0220Y0320R090 S1      
327GND              R5899 -1          A01X+170292Y+020800X0198Y0197     S1      
317GND              VIA   -    MD0100PA00X+172900Y+018350X0200Y         S0      
327GND              R387  -1          A01X+172608Y+018350X0198Y0197R180 S1      
317GND              VIA   -    MD0100PA00X+100100Y+022850X0200Y         S0      
317GND              VIA   -    MD0100PA00X+101000Y+022850X0200Y         S0      
317GND              VIA   -    MD0100PA00X+100700Y+022850X0200Y         S0      
317GND              VIA   -    MD0100PA00X+100400Y+022850X0200Y         S0      
317GND              VIA   -    MD0100PA00X+101300Y+022850X0200Y         S0      
317GND              VIA   -    MD0100PA00X+097450Y+022850X0200Y         S0      
317GND              VIA   -    MD0100PA00X+097750Y+022850X0200Y         S0      
317GND              VIA   -    MD0100PA00X+098050Y+022850X0200Y         S0      
317GND              VIA   -    MD0100PA00X+098350Y+022850X0200Y         S0      
317GND              VIA   -    MD0100PA00X+098650Y+022850X0200Y         S0      
327GND              C69   -2          A10X+102900Y+020350X0280Y0320R270 S2      
317GND              VIA   -    MD0100PA00X+103010Y+020750X0200Y         S0      
327GND              R399  -2          A10X+102768Y+020850X0198Y0197R180 S2      
317GND              VIA   -    MD0100PA00X+135500Y+020440X0200Y         S0      
327GND              PC8   -1          A10X+134700Y+020440X0280Y0320R090 S2      
317GND              VIA   -    MD0100PA00X+135510Y+016000X0200Y         S0      
327GND              PC583 -1          A10X+134700Y+016030X0280Y0320R090 S2      
317GND              VIA   -    M      A01X+020060Y+010906X0200Y         S2      
017GND              VIA   -    M      A10X+020060Y+010906X0260Y         S2      
017GND                    -    MD0100PA00X+020060Y+010906                       
327GND              PU4   -S          A01X+019725Y+010906X0240Y0320R090 S1      
317GND              VIA   -    MD0100PA00X+020510Y+012300X0200Y         S0      
327GND              PQ18  -E          A01X+020068Y+012300X0400Y0500R090 S1      
317GND              VIA   -    MD0100PA00X+152710Y+010850X0200Y         S0      
327GND              PQ17  -E          A01X+153110Y+010850X0400Y0500R270 S1      
317GND              VIA   -    MD0100PA00X+153160Y+009694X0200Y         S0      
327GND              PU3   -S          A01X+153485Y+009694X0240Y0320R270 S1      
327GND              PC487 -2          A10X+113890Y+032100X0460Y0620     S2      
317GND              VIA   -    MD0100PA00X+114310Y+032000X0200Y         S0      
317GND              VIA   -    MD0100PA00X+114310Y+032250X0200Y         S0      
317GND              VIA   -    MD0100PA00X+115460Y+032105X0200Y         S0      
327GND              PJ1   -2          A10X+115460Y+031795X0280Y0320     S2      
317GND              VIA   -    MD0100PA00X+114160Y+030516X0200Y         S0      
327GND              U31   -4          A10X+114562Y+030516X0150Y0460R090 S2      
317GND              JP3   -2   MD0460PA00X+086640Y+037220X0660Y    R270 S3      
317GND              VIA   -    MD0100PA00X+177614Y+036440X0200Y         S0      
317GND              J11   -S3  MD0410PA00X+185896Y+032421X0610Y    R090 S3      
317GND              J11   -S1  MD0410PA00X+185896Y+031421X0610Y    R090 S3      
317GND              J11   -P4  MD0410PA00X+185677Y+026043X0610Y    R090 S3      
317GND              J11   -P3  MD0410PA00X+185677Y+025043X0610Y    R090 S3      
317GND              J11   -P2  MD0410PA00X+185677Y+024043X0610Y    R090 S3      
317GND              J11   -P1  MD0410PA00X+185677Y+023043X0610Y    R090 S3      
317GND              VIA   -    MD0100PA00X+160210Y+006250X0200Y         S0      
317GND              VIA   -    MD0100PA00X+160210Y+006600X0200Y         S0      
317GND              VIA   -    MD0100PA00X+160210Y+006950X0200Y         S0      
317GND              VIA   -    MD0100PA00X+160210Y+008200X0200Y         S0      
317GND              VIA   -    MD0100PA00X+160210Y+008550X0200Y         S0      
317GND              VIA   -    MD0100PA00X+160210Y+008900X0200Y         S0      
317GND              VIA   -    MD0100PA00X+173360Y+038750X0200Y    R270 S0      
317GND              VIA   -    MD0100PA00X+173110Y+038750X0200Y    R270 S0      
317GND              VIA   -    MD0100PA00X+172860Y+038750X0200Y    R270 S0      
317GND              VIA   -    MD0100PA00X+172860Y+039750X0200Y    R090 S0      
317GND              VIA   -    MD0100PA00X+173110Y+039750X0200Y    R090 S0      
317GND              VIA   -    MD0100PA00X+173360Y+039750X0200Y    R090 S0      
317GND              VIA   -    MD0100PA00X+174060Y+023300X0200Y    R180 S0      
317GND              VIA   -    MD0100PA00X+175160Y+023300X0200Y    R180 S0      
317GND              VIA   -    MD0100PA00X+177610Y+036850X0200Y         S0      
317GND              VIA   -    MD0100PA00X+177610Y+037150X0200Y         S0      
317GND              VIA   -    MD0100PA00X+178960Y+024350X0200Y    R180 S0      
317GND              VIA   -    MD0100PA00X+174060Y+024050X0200Y    R180 S0      
317GND              VIA   -    MD0100PA00X+174060Y+023800X0200Y    R180 S0      
317GND              VIA   -    MD0100PA00X+174060Y+023550X0200Y    R180 S0      
317GND              VIA   -    MD0100PA00X+175160Y+023550X0200Y    R180 S0      
317GND              VIA   -    MD0100PA00X+175160Y+023800X0200Y    R180 S0      
317GND              VIA   -    MD0100PA00X+175160Y+024050X0200Y    R180 S0      
317GND              VIA   -    MD0100PA00X+161580Y+007670X0200Y    R270 S0      
317GND              VIA   -    MD0100PA00X+161580Y+007970X0200Y    R270 S0      
317GND              VIA   -    MD0100PA00X+161580Y+008270X0200Y    R270 S0      
317GND              VIA   -    MD0100PA00X+161880Y+008270X0200Y    R270 S0      
317GND              VIA   -    MD0100PA00X+161880Y+007970X0200Y    R270 S0      
317GND              VIA   -    M      A01X+161880Y+007670X0200Y    R270 S2      
017GND              VIA   -    M      A10X+161880Y+007670X0260Y    R270 S2      
017GND                    -    MD0100PA00X+161880Y+007670                       
317GND              VIA   -    MD0100PA00X+160610Y+006250X0200Y         S0      
317GND              VIA   -    MD0100PA00X+160610Y+006600X0200Y         S0      
317GND              VIA   -    MD0100PA00X+160610Y+006950X0200Y         S0      
317GND              VIA   -    MD0100PA00X+160910Y+006250X0200Y         S0      
317GND              VIA   -    MD0100PA00X+160910Y+006600X0200Y         S0      
317GND              VIA   -    MD0100PA00X+160910Y+006950X0200Y         S0      
317GND              VIA   -    MD0100PA00X+160610Y+008200X0200Y         S0      
317GND              VIA   -    MD0100PA00X+160610Y+008550X0200Y         S0      
317GND              VIA   -    MD0100PA00X+160610Y+008900X0200Y         S0      
317GND              VIA   -    MD0100PA00X+160910Y+008200X0200Y         S0      
317GND              VIA   -    MD0100PA00X+160910Y+008550X0200Y         S0      
317GND              VIA   -    MD0100PA00X+160910Y+008900X0200Y         S0      
317GND              VIA   -    MD0100PA00X+161410Y+013000X0200Y         S0      
317GND              VIA   -    MD0100PA00X+161410Y+012000X0200Y         S0      
317GND              VIA   -    MD0100PA00X+161410Y+011500X0200Y         S0      
317GND              VIA   -    MD0100PA00X+161410Y+011000X0200Y         S0      
317GND              VIA   -    MD0100PA00X+170110Y+017850X0200Y         S0      
327GND              R58   -2          A01X+169010Y+013598X0198Y0197R090 S1      
317GND              VIA   -    M      A01X+169260Y+013598X0200Y    R180 S2      
017GND              VIA   -    M      A10X+169260Y+013598X0260Y    R180 S2      
017GND                    -    MD0100PA00X+169260Y+013598                       
317GND              VIA   -    M      A01X+170208Y+020550X0200Y         S2      
017GND              VIA   -    M      A10X+170208Y+020550X0260Y         S2      
017GND                    -    MD0100PA00X+170208Y+020550                       
327GND              R100  -2          A01X+168358Y+017000X0198Y0197     S1      
317GND              VIA   -    MD0100PA00X+168598Y+017000X0200Y         S0      
327GND              R99   -2          A01X+168358Y+017550X0198Y0197     S1      
317GND              VIA   -    MD0100PA00X+168598Y+017550X0200Y         S0      
327GND              R56   -2          A01X+168358Y+018100X0198Y0197     S1      
317GND              VIA   -    MD0100PA00X+168598Y+018100X0200Y         S0      
317GND              VIA   -    M      A01X+167918Y+019476X0200Y         S2      
017GND              VIA   -    M      A10X+167918Y+019476X0260Y         S2      
017GND                    -    MD0100PA00X+167918Y+019476                       
327GND              R138  -2          A01X+168358Y+014800X0198Y0197     S1      
317GND              VIA   -    MD0100PA00X+168598Y+014800X0200Y         S0      
327GND              R137  -2          A01X+168358Y+015350X0198Y0197     S1      
317GND              VIA   -    M      A01X+168598Y+015350X0200Y         S2      
017GND              VIA   -    M      A10X+168598Y+015350X0260Y         S2      
017GND                    -    MD0100PA00X+168598Y+015350                       
327GND              R136  -2          A01X+168358Y+015900X0198Y0197     S1      
317GND              VIA   -    MD0100PA00X+168598Y+015900X0200Y         S0      
327GND              R101  -2          A01X+168358Y+016450X0198Y0197     S1      
317GND              VIA   -    MD0100PA00X+168598Y+016450X0200Y         S0      
327GND              U8    -12         A01X+164350Y+015292X0140Y0590R270 S1      
317GND              VIA   -    M      A01X+163500Y+015292X0200Y    R090 S2      
017GND              VIA   -    M      A10X+163500Y+015292X0260Y    R090 S2      
017GND                    -    MD0100PA00X+163500Y+015292                       
317GND              VIA   -    M      A01X+170252Y+012950X0200Y         S2      
017GND              VIA   -    M      A10X+170252Y+012950X0260Y         S2      
017GND                    -    MD0100PA00X+170252Y+012950                       
327GND              R24   -2   M      A01X+170492Y+012950X0198Y0197R180 S1      
327GND              R25   -2          A01X+170492Y+013450X0198Y0197R180 S1      
327GND              R186  -1          A01X+177008Y+017400X0198Y0197R180 S1      
317GND              VIA   -    MD0100PA00X+177250Y+017400X0200Y         S0      
317GND              VIA   -    M      A01X+176948Y+016850X0200Y         S2      
017GND              VIA   -    M      A10X+176948Y+016850X0260Y         S2      
017GND                    -    MD0100PA00X+176948Y+016850                       
327GND              C1    -2          A01X+176708Y+016850X0198Y0197     S1      
327GND              U21   -3          A01X+173768Y+017376X0180Y0520R270 S1      
317GND              VIA   -    M      A01X+173350Y+017376X0200Y         S2      
017GND              VIA   -    M      A10X+173350Y+017376X0260Y         S2      
017GND                    -    MD0100PA00X+173350Y+017376                       
327GND              U1    -4          A01X+173371Y+015916X0140Y0560R270 S1      
317GND              VIA   -    M      A01X+172941Y+015916X0200Y         S2      
017GND              VIA   -    M      A10X+172941Y+015916X0260Y         S2      
017GND                    -    MD0100PA00X+172941Y+015916                       
327GND              R383  -1          A01X+172292Y+017950X0198Y0197     S1      
317GND              VIA   -    M      A01X+172010Y+017950X0200Y         S2      
017GND              VIA   -    M      A10X+172010Y+017950X0260Y         S2      
017GND                    -    MD0100PA00X+172010Y+017950                       
327GND              U26   -S          A01X+173874Y+018806X0320Y0360     S1      
317GND              VIA   -    M      A01X+173874Y+019150X0200Y         S2      
017GND              VIA   -    M      A10X+173874Y+019150X0260Y         S2      
017GND                    -    MD0100PA00X+173874Y+019150                       
327GND              U2    -4          A01X+173371Y+014366X0140Y0560R270 S1      
317GND              VIA   -    M      A01X+172941Y+014366X0200Y         S2      
017GND              VIA   -    M      A10X+172941Y+014366X0260Y         S2      
017GND                    -    MD0100PA00X+172941Y+014366                       
327GND              U18   -7   M      A01X+173210Y+010450X0220Y0680R270 S1      
317GND              VIA   -    M      A01X+172720Y+010450X0200Y    R270 S2      
017GND              VIA   -    M      A10X+172720Y+010450X0260Y    R270 S2      
017GND                    -    MD0100PA00X+172720Y+010450                       
317GND              VIA   -    MD0100PA00X+177738Y+034829X0200Y    R270 S0      
327GND              R393  -2          A01X+177498Y+034829X0198Y0197     S1      
317GND              VIA   -    MD0100PA00X+176645Y+024280X0200Y    R180 S0      
317GND              VIA   -    MD0100PA00X+176645Y+023980X0200Y    R180 S0      
317GND              VIA   -    MD0100PA00X+177545Y+024280X0200Y    R180 S0      
317GND              VIA   -    MD0100PA00X+177545Y+023980X0200Y    R180 S0      
317GND              VIA   -    MD0100PA00X+178395Y+024280X0200Y    R180 S0      
317GND              VIA   -    MD0100PA00X+178395Y+023980X0200Y    R180 S0      
327GND              PU5   -4          A01X+176273Y+033408X0070Y0320R270 S1      
327GND              PR113 -2          A01X+177488Y+032832X0198Y0197     S1      
327GND              PR114 -2          A01X+177182Y+033650X0198Y0197R270 S1      
327GND              PC53  -2          A01X+177488Y+033232X0198Y0197     S1      
327GND              PU5   -6          A01X+176273Y+033723X0070Y0320R270 S1      
327GND              PU5   -2          A01X+176273Y+033093X0070Y0320R270 S1      
317GND              VIA   -    MD0100PA00X+176715Y+033331X0200Y    R270 S0      
317GND              VIA   -    M      A01X+176245Y+032035X0200Y    R270 S2      
017GND              VIA   -    M      A10X+176245Y+032035X0260Y    R270 S2      
017GND                    -    MD0100PA00X+176245Y+032035                       
317GND              VIA   -    MD0100PA00X+177753Y+032832X0200Y    R270 S0      
317GND              VIA   -    MD0100PA00X+177746Y+033232X0200Y    R270 S0      
317GND              VIA   -    MD0100PA00X+174491Y+033414X0200Y    R270 S0      
317GND              VIA   -    MD0100PA00X+174491Y+033694X0200Y    R270 S0      
317GND              VIA   -    MD0100PA00X+174491Y+033974X0200Y    R270 S0      
317GND              VIA   -    MD0100PA00X+174791Y+033414X0200Y    R270 S0      
317GND              VIA   -    MD0100PA00X+174791Y+033694X0200Y    R270 S0      
317GND              VIA   -    MD0100PA00X+174791Y+033974X0200Y    R270 S0      
317GND              VIA   -    MD0100PA00X+174211Y+033404X0200Y    R270 S0      
317GND              VIA   -    MD0100PA00X+174211Y+033684X0200Y    R270 S0      
317GND              VIA   -    MD0100PA00X+174211Y+033964X0200Y    R270 S0      
317GND              VIA   -    MD0100PA00X+177610Y+036150X0200Y         S0      
317GND              VIA   -    MD0100PA00X+174724Y+035956X0200Y         S0      
317GND              VIA   -    M      A01X+174724Y+035599X0200Y         S2      
017GND              VIA   -    M      A10X+174724Y+035599X0260Y         S2      
017GND                    -    MD0100PA00X+174724Y+035599                       
317GND              VIA   -    MD0100PA00X+174742Y+035182X0200Y         S0      
317GND              VIA   -    MD0100PA00X+174491Y+034254X0200Y    R270 S0      
317GND              VIA   -    MD0100PA00X+174491Y+034534X0200Y    R270 S0      
317GND              VIA   -    MD0100PA00X+174791Y+034254X0200Y    R270 S0      
317GND              VIA   -    MD0100PA00X+174791Y+034534X0200Y    R270 S0      
317GND              VIA   -    MD0100PA00X+175129Y+034523X0200Y         S0      
317GND              VIA   -    MD0100PA00X+174742Y+034829X0200Y    R270 S0      
317GND              VIA   -    MD0100PA00X+174211Y+034244X0200Y    R270 S0      
317GND              VIA   -    MD0100PA00X+174211Y+034524X0200Y    R270 S0      
317GND              PC34  -2   MD0500PA00X+016678Y+052047X0700Y         S3      
317GND              PC35  -2   MD0500PA00X+024378Y+052047X0700Y         S3      
317GND              PC36  -2   MD0500PA00X+016678Y+044047X0700Y         S3      
317GND              PC37  -2   MD0500PA00X+024378Y+044047X0700Y         S3      
317GND              PC38  -2   MD0500PA00X+016678Y+036047X0700Y         S3      
317GND              PC39  -2   MD0500PA00X+024378Y+036047X0700Y         S3      
317GND              PC44  -2   MD0500PA00X+016678Y+028047X0700Y         S3      
317GND              PC45  -2   MD0500PA00X+024378Y+028047X0700Y         S3      
317GND              PC46  -2   MD0500PA00X+016678Y+020047X0700Y         S3      
317GND              PC47  -2   MD0500PA00X+024378Y+020047X0700Y         S3      
327GND              PR106 -2   M      A01X+019769Y+009100X0630Y1380     S1      
327GND              PR107 -2   M      A01X+019769Y+007300X0630Y1380     S1      
317GND              PC28  -2   MD0500PA00X+148850Y+052047X0700Y         S3      
317GND              PC29  -2   MD0500PA00X+156550Y+052047X0700Y         S3      
317GND              PC30  -2   MD0500PA00X+148850Y+044047X0700Y         S3      
317GND              PC31  -2   MD0500PA00X+156550Y+044047X0700Y         S3      
317GND              PC32  -2   MD0500PA00X+148850Y+036047X0700Y         S3      
317GND              PC33  -2   MD0500PA00X+156550Y+036047X0700Y         S3      
317GND              PC40  -2   MD0500PA00X+148850Y+028047X0700Y         S3      
317GND              PC41  -2   MD0500PA00X+156550Y+028047X0700Y         S3      
317GND              PC42  -2   MD0500PA00X+148850Y+020047X0700Y         S3      
317GND              PC43  -2   MD0500PA00X+156550Y+020047X0700Y         S3      
317GND              VIA   -    MD0100PA00X+150846Y+000300X0200Y         S0      
317GND              VIA   -    MD0100PA00X+152846Y+000300X0200Y         S0      
317GND              VIA   -    MD0100PA00X+154846Y+000300X0200Y         S0      
317GND              VIA   -    MD0100PA00X+156846Y+000300X0200Y         S0      
317GND              VIA   -    MD0100PA00X+158846Y+000300X0200Y         S0      
317GND              VIA   -    MD0100PA00X+160846Y+000300X0200Y         S0      
317GND              VIA   -    MD0100PA00X+162846Y+000300X0200Y         S0      
317GND              VIA   -    MD0100PA00X+164846Y+000300X0200Y         S0      
317GND              VIA   -    MD0100PA00X+170846Y+000300X0200Y         S0      
317GND              VIA   -    MD0100PA00X+172926Y+002535X0200Y         S0      
317GND              VIA   -    MD0100PA00X+172926Y+004535X0200Y         S0      
317GND              VIA   -    MD0100PA00X+173279Y+005846X0200Y         S0      
317GND              VIA   -    MD0100PA00X+175364Y+006904X0200Y         S0      
317GND              VIA   -    MD0100PA00X+177364Y+006904X0200Y         S0      
317GND              VIA   -    MD0100PA00X+179364Y+006904X0200Y         S0      
317GND              VIA   -    MD0100PA00X+181364Y+006904X0200Y         S0      
317GND              VIA   -    MD0100PA00X+183364Y+006904X0200Y         S0      
317GND              VIA   -    MD0100PA00X+185364Y+006904X0200Y         S0      
317GND              VIA   -    MD0100PA00X+187101Y+009391X0200Y         S0      
317GND              VIA   -    MD0100PA00X+187101Y+011711X0200Y         S0      
317GND              VIA   -    MD0100PA00X+187101Y+013711X0200Y         S0      
317GND              VIA   -    MD0100PA00X+187101Y+015711X0200Y         S0      
317GND              VIA   -    MD0100PA00X+187101Y+017711X0200Y         S0      
317GND              VIA   -    MD0100PA00X+187101Y+019711X0200Y         S0      
317GND              VIA   -    MD0100PA00X+187101Y+021711X0200Y         S0      
317GND              VIA   -    MD0100PA00X+187101Y+023711X0200Y         S0      
317GND              VIA   -    MD0100PA00X+187101Y+025711X0200Y         S0      
317GND              VIA   -    MD0100PA00X+187101Y+027711X0200Y         S0      
317GND              VIA   -    MD0100PA00X+187101Y+029711X0200Y         S0      
317GND              VIA   -    MD0100PA00X+187101Y+031711X0200Y         S0      
317GND              VIA   -    MD0100PA00X+187101Y+033711X0200Y         S0      
317GND              VIA   -    MD0100PA00X+187101Y+035711X0200Y         S0      
317GND              VIA   -    MD0100PA00X+187101Y+037711X0200Y         S0      
317GND              VIA   -    MD0100PA00X+187101Y+039711X0200Y         S0      
317GND              VIA   -    MD0100PA00X+187101Y+041711X0200Y         S0      
317GND              VIA   -    MD0100PA00X+187101Y+043711X0200Y         S0      
317GND              VIA   -    MD0100PA00X+187101Y+045711X0200Y         S0      
317GND              VIA   -    MD0100PA00X+187101Y+047711X0200Y         S0      
317GND              VIA   -    MD0100PA00X+187101Y+049711X0200Y         S0      
317GND              VIA   -    MD0100PA00X+185551Y+051570X0200Y         S0      
317GND              VIA   -    MD0100PA00X+183545Y+051575X0200Y         S0      
317GND              VIA   -    MD0100PA00X+181545Y+051575X0200Y         S0      
317GND              VIA   -    MD0100PA00X+177545Y+051575X0200Y         S0      
317GND              VIA   -    MD0100PA00X+175545Y+051575X0200Y         S0      
317GND              VIA   -    MD0100PA00X+172928Y+054275X0200Y         S0      
317GND              VIA   -    MD0100PA00X+172928Y+056275X0200Y         S0      
317GND              VIA   -    MD0100PA00X+172928Y+058275X0200Y         S0      
317GND              VIA   -    MD0100PA00X+172928Y+060275X0200Y         S0      
317GND              VIA   -    MD0100PA00X+170869Y+062019X0200Y         S0      
317GND              VIA   -    MD0100PA00X+168869Y+062019X0200Y         S0      
317GND              VIA   -    MD0100PA00X+166868Y+062023X0200Y         S0      
317GND              VIA   -    MD0100PA00X+164868Y+062023X0200Y         S0      
317GND              VIA   -    MD0100PA00X+162866Y+062026X0200Y         S0      
317GND              VIA   -    MD0100PA00X+161353Y+062722X0200Y         S0      
317GND              VIA   -    MD0100PA00X+160723Y+065045X0200Y         S0      
317GND              VIA   -    MD0100PA00X+160260Y+066763X0200Y         S0      
317GND              VIA   -    MD0100PA00X+158583Y+067278X0200Y         S0      
317GND              VIA   -    MD0100PA00X+156583Y+067278X0200Y         S0      
317GND              VIA   -    MD0100PA00X+154583Y+067278X0200Y         S0      
317GND              VIA   -    MD0100PA00X+152583Y+067278X0200Y         S0      
317GND              VIA   -    MD0100PA00X+150583Y+067278X0200Y         S0      
317GND              VIA   -    MD0100PA00X+148583Y+067278X0200Y         S0      
317GND              VIA   -    MD0100PA00X+146583Y+067278X0200Y         S0      
317GND              VIA   -    MD0100PA00X+144583Y+067278X0200Y         S0      
317GND              VIA   -    MD0100PA00X+142875Y+067055X0200Y         S0      
317GND              VIA   -    MD0100PA00X+142034Y+065539X0200Y         S0      
317GND              VIA   -    MD0100PA00X+142034Y+063539X0200Y         S0      
317GND              VIA   -    MD0100PA00X+140304Y+062018X0200Y         S0      
317GND              VIA   -    MD0100PA00X+138964Y+061272X0200Y         S0      
317GND              VIA   -    MD0100PA00X+138688Y+059454X0200Y         S0      
317GND              VIA   -    MD0100PA00X+138688Y+057454X0200Y         S0      
317GND              VIA   -    MD0100PA00X+138688Y+055454X0200Y         S0      
317GND              VIA   -    MD0100PA00X+138688Y+053454X0200Y         S0      
317GND              VIA   -    MD0100PA00X+138688Y+051454X0200Y         S0      
317GND              VIA   -    MD0100PA00X+138688Y+049454X0200Y         S0      
317GND              VIA   -    MD0100PA00X+138688Y+047454X0200Y         S0      
317GND              VIA   -    MD0100PA00X+138688Y+045454X0200Y         S0      
317GND              VIA   -    MD0100PA00X+138688Y+043454X0200Y         S0      
317GND              VIA   -    MD0100PA00X+022141Y+000304X0200Y         S0      
317GND              VIA   -    MD0100PA00X+018141Y+000304X0200Y         S0      
317GND              VIA   -    MD0100PA00X+020141Y+000304X0200Y         S0      
317GND              VIA   -    MD0100PA00X+014141Y+000304X0200Y         S0      
317GND              VIA   -    MD0100PA00X+016141Y+000304X0200Y         S0      
317GND              VIA   -    MD0100PA00X+012141Y+000304X0200Y         S0      
317GND              VIA   -    MD0100PA00X+010141Y+000304X0200Y         S0      
317GND              VIA   -    MD0100PA00X+008141Y+000304X0200Y         S0      
317GND              VIA   -    MD0100PA00X+003071Y+000301X0200Y         S0      
317GND              VIA   -    MD0100PA00X+001049Y+000583X0200Y         S0      
317GND              VIA   -    MD0100PA00X+000302Y+002393X0200Y         S0      
317GND              VIA   -    MD0100PA00X+000302Y+004393X0200Y         S0      
317GND              VIA   -    MD0100PA00X+000302Y+006393X0200Y         S0      
317GND              VIA   -    MD0100PA00X+000302Y+008393X0200Y         S0      
317GND              VIA   -    MD0100PA00X+000302Y+010393X0200Y         S0      
317GND              VIA   -    MD0100PA00X+000302Y+012393X0200Y         S0      
317GND              VIA   -    MD0100PA00X+000302Y+014393X0200Y         S0      
317GND              VIA   -    MD0100PA00X+000302Y+016393X0200Y         S0      
317GND              VIA   -    MD0100PA00X+000302Y+018393X0200Y         S0      
317GND              VIA   -    MD0100PA00X+000302Y+020393X0200Y         S0      
317GND              VIA   -    MD0100PA00X+000302Y+022393X0200Y         S0      
317GND              VIA   -    MD0100PA00X+000302Y+024393X0200Y         S0      
317GND              VIA   -    MD0100PA00X+000302Y+026393X0200Y         S0      
317GND              VIA   -    MD0100PA00X+000302Y+028393X0200Y         S0      
317GND              VIA   -    MD0100PA00X+000302Y+030393X0200Y         S0      
317GND              VIA   -    MD0100PA00X+000302Y+032393X0200Y         S0      
317GND              VIA   -    MD0100PA00X+000302Y+034393X0200Y         S0      
317GND              VIA   -    MD0100PA00X+000302Y+036393X0200Y         S0      
317GND              VIA   -    MD0100PA00X+000302Y+038393X0200Y         S0      
317GND              VIA   -    MD0100PA00X+000302Y+040393X0200Y         S0      
317GND              VIA   -    MD0100PA00X+000302Y+042393X0200Y         S0      
317GND              VIA   -    MD0100PA00X+000302Y+044393X0200Y         S0      
317GND              VIA   -    MD0100PA00X+000302Y+046393X0200Y         S0      
317GND              VIA   -    MD0100PA00X+000302Y+048393X0200Y         S0      
317GND              VIA   -    MD0100PA00X+000302Y+050393X0200Y         S0      
317GND              VIA   -    MD0100PA00X+000302Y+052393X0200Y         S0      
317GND              VIA   -    MD0100PA00X+000302Y+054393X0200Y         S0      
317GND              VIA   -    MD0100PA00X+000302Y+056393X0200Y         S0      
317GND              VIA   -    MD0100PA00X+000302Y+058393X0200Y         S0      
317GND              VIA   -    MD0100PA00X+000302Y+060393X0200Y         S0      
317GND              VIA   -    MD0100PA00X+001564Y+061972X0200Y         S0      
317GND              VIA   -    MD0100PA00X+003546Y+062019X0200Y         S0      
317GND              VIA   -    MD0100PA00X+005546Y+062019X0200Y         S0      
317GND              VIA   -    MD0100PA00X+009546Y+062019X0200Y         S0      
317GND              VIA   -    MD0100PA00X+007546Y+062019X0200Y         S0      
317GND              VIA   -    MD0100PA00X+011492Y+062398X0200Y         S0      
317GND              VIA   -    MD0100PA00X+012490Y+064010X0200Y         S0      
317GND              VIA   -    MD0100PA00X+015478Y+067278X0200Y         S0      
317GND              VIA   -    MD0100PA00X+017478Y+067278X0200Y         S0      
317GND              VIA   -    MD0100PA00X+019478Y+067278X0200Y         S0      
317GND              VIA   -    MD0100PA00X+021478Y+067278X0200Y         S0      
317GND              VIA   -    MD0100PA00X+023478Y+067278X0200Y         S0      
317GND              VIA   -    MD0100PA00X+025478Y+067278X0200Y         S0      
317GND              VIA   -    MD0100PA00X+027478Y+067278X0200Y         S0      
317GND              VIA   -    MD0100PA00X+029478Y+067278X0200Y         S0      
317GND              VIA   -    MD0100PA00X+031196Y+065152X0200Y         S0      
317GND              VIA   -    MD0100PA00X+033128Y+062001X0200Y         S0      
317GND              VIA   -    MD0100PA00X+034212Y+061351X0200Y         S0      
317GND              VIA   -    MD0100PA00X+034541Y+059502X0200Y         S0      
317GND              VIA   -    MD0100PA00X+034541Y+057502X0200Y         S0      
317GND              VIA   -    MD0100PA00X+034541Y+055502X0200Y         S0      
317GND              VIA   -    MD0100PA00X+034541Y+053502X0200Y         S0      
317GND              VIA   -    MD0100PA00X+034541Y+051502X0200Y         S0      
317GND              VIA   -    MD0100PA00X+034541Y+049502X0200Y         S0      
317GND              VIA   -    MD0100PA00X+034541Y+047502X0200Y         S0      
317GND              VIA   -    MD0100PA00X+034541Y+045502X0200Y         S0      
317GND              VIA   -    MD0100PA00X+034541Y+043502X0200Y         S0      
317GND              VIA   -    MD0100PA00X+035002Y+041834X0200Y         S0      
317GND              VIA   -    MD0100PA00X+036213Y+040661X0200Y         S0      
317GND              VIA   -    MD0100PA00X+032077Y+003921X0200Y         S0      
317GND              VIA   -    MD0100PA00X+032377Y+003921X0200Y         S0      
317GND              VIA   -    MD0100PA00X+031777Y+003921X0200Y         S0      
317GND              VIA   -    MD0100PA00X+031477Y+003921X0200Y         S0      
317GND              VIA   -    MD0100PA00X+037519Y+003842X0200Y         S0      
317GND              VIA   -    MD0100PA00X+037819Y+003842X0200Y         S0      
317GND              VIA   -    MD0100PA00X+037219Y+003842X0200Y         S0      
317GND              VIA   -    MD0100PA00X+036919Y+003842X0200Y         S0      
317GND              VIA   -    MD0100PA00X+050792Y+003746X0200Y         S0      
317GND              VIA   -    MD0100PA00X+051092Y+003746X0200Y         S0      
317GND              VIA   -    MD0100PA00X+050492Y+003746X0200Y         S0      
317GND              VIA   -    MD0100PA00X+050192Y+003746X0200Y         S0      
317GND              VIA   -    MD0100PA00X+142531Y+004048X0200Y         S0      
317GND              VIA   -    MD0100PA00X+141631Y+004048X0200Y         S0      
317GND              VIA   -    MD0100PA00X+141931Y+004048X0200Y         S0      
317GND              VIA   -    MD0100PA00X+142231Y+004048X0200Y         S0      
317GND              VIA   -    MD0100PA00X+135831Y+003889X0200Y         S0      
317GND              VIA   -    MD0100PA00X+134931Y+003889X0200Y         S0      
317GND              VIA   -    MD0100PA00X+135231Y+003889X0200Y         S0      
317GND              VIA   -    MD0100PA00X+135531Y+003889X0200Y         S0      
317GND              VIA   -    MD0100PA00X+122987Y+003848X0200Y         S0      
317GND              VIA   -    MD0100PA00X+122087Y+003848X0200Y         S0      
317GND              VIA   -    MD0100PA00X+122387Y+003848X0200Y         S0      
317GND              VIA   -    MD0100PA00X+122687Y+003848X0200Y         S0      
317GND              VIA   -    MD0100PA00X+124893Y+035615X0200Y         S0      
317GND              VIA   -    MD0100PA00X+124893Y+035915X0200Y         S0      
317GND              VIA   -    MD0100PA00X+124593Y+035615X0200Y         S0      
317GND              VIA   -    MD0100PA00X+124593Y+035915X0200Y         S0      
317GND              VIA   -    MD0100PA00X+124293Y+035615X0200Y         S0      
317GND              VIA   -    M      A01X+124293Y+035915X0200Y         S2      
017GND              VIA   -    M      A10X+124293Y+035915X0260Y         S2      
017GND                    -    MD0100PA00X+124293Y+035915                       
317GND              VIA   -    MD0100PA00X+129211Y+037531X0200Y         S0      
317GND              VIA   -    MD0100PA00X+129211Y+037831X0200Y         S0      
317GND              VIA   -    MD0100PA00X+128911Y+037531X0200Y         S0      
317GND              VIA   -    MD0100PA00X+128911Y+037831X0200Y         S0      
317GND              VIA   -    MD0100PA00X+128611Y+037531X0200Y         S0      
317GND              VIA   -    M      A01X+128611Y+037831X0200Y         S2      
017GND              VIA   -    M      A10X+128611Y+037831X0260Y         S2      
017GND                    -    MD0100PA00X+128611Y+037831                       
317GND              VIA   -    MD0100PA00X+065478Y+009900X0200Y         S0      
317GND              VIA   -    MD0100PA00X+065778Y+009900X0200Y         S0      
317GND              VIA   -    MD0100PA00X+065478Y+009600X0200Y         S0      
317GND              VIA   -    M      A01X+065778Y+009600X0200Y         S2      
017GND              VIA   -    M      A10X+065778Y+009600X0260Y         S2      
017GND                    -    MD0100PA00X+065778Y+009600                       
317GND              VIA   -    MD0100PA00X+065178Y+009600X0200Y         S0      
317GND              VIA   -    MD0100PA00X+064878Y+009600X0200Y         S0      
317GND              VIA   -    MD0100PA00X+064578Y+009600X0200Y         S0      
317GND              VIA   -    MD0100PA00X+065178Y+009900X0200Y         S0      
317GND              VIA   -    MD0100PA00X+064878Y+009900X0200Y         S0      
317GND              VIA   -    MD0100PA00X+064578Y+009900X0200Y         S0      
317GND              VIA   -    MD0100PA00X+065478Y+004350X0200Y         S0      
317GND              VIA   -    MD0100PA00X+065778Y+004350X0200Y         S0      
317GND              VIA   -    MD0100PA00X+065478Y+004050X0200Y         S0      
317GND              VIA   -    M      A01X+065778Y+004050X0200Y         S2      
017GND              VIA   -    M      A10X+065778Y+004050X0260Y         S2      
017GND                    -    MD0100PA00X+065778Y+004050                       
317GND              VIA   -    MD0100PA00X+065178Y+004050X0200Y         S0      
317GND              VIA   -    MD0100PA00X+064878Y+004050X0200Y         S0      
317GND              VIA   -    MD0100PA00X+064578Y+004050X0200Y         S0      
317GND              VIA   -    MD0100PA00X+065178Y+004350X0200Y         S0      
317GND              VIA   -    MD0100PA00X+064878Y+004350X0200Y         S0      
317GND              VIA   -    MD0100PA00X+064578Y+004350X0200Y         S0      
317GND              VIA   -    MD0100PA00X+108650Y+004350X0200Y         S0      
317GND              VIA   -    MD0100PA00X+108350Y+004350X0200Y         S0      
317GND              VIA   -    MD0100PA00X+108050Y+004350X0200Y         S0      
317GND              VIA   -    MD0100PA00X+108650Y+004050X0200Y         S0      
317GND              VIA   -    MD0100PA00X+108350Y+004050X0200Y         S0      
317GND              VIA   -    MD0100PA00X+108050Y+004050X0200Y         S0      
317GND              VIA   -    MD0100PA00X+107450Y+004050X0200Y         S0      
317GND              VIA   -    MD0100PA00X+107750Y+004050X0200Y         S0      
317GND              VIA   -    M      A01X+107450Y+004350X0200Y         S2      
017GND              VIA   -    M      A10X+107450Y+004350X0260Y         S2      
017GND                    -    MD0100PA00X+107450Y+004350                       
317GND              VIA   -    MD0100PA00X+107750Y+004350X0200Y         S0      
317GND              VIA   -    MD0100PA00X+108650Y+009900X0200Y         S0      
317GND              VIA   -    MD0100PA00X+108350Y+009900X0200Y         S0      
317GND              VIA   -    MD0100PA00X+108050Y+009900X0200Y         S0      
317GND              VIA   -    MD0100PA00X+108650Y+009600X0200Y         S0      
317GND              VIA   -    MD0100PA00X+108350Y+009600X0200Y         S0      
317GND              VIA   -    MD0100PA00X+108050Y+009600X0200Y         S0      
317GND              VIA   -    MD0100PA00X+107450Y+009600X0200Y         S0      
317GND              VIA   -    MD0100PA00X+107750Y+009600X0200Y         S0      
317GND              VIA   -    M      A01X+107450Y+009900X0200Y         S2      
017GND              VIA   -    M      A10X+107450Y+009900X0260Y         S2      
017GND                    -    MD0100PA00X+107450Y+009900                       
317GND              VIA   -    MD0100PA00X+107750Y+009900X0200Y         S0      
317GND              VIA   -    MD0100PA00X+074950Y+023150X0200Y         S0      
317GND              VIA   -    MD0100PA00X+075250Y+023150X0200Y         S0      
317GND              VIA   -    MD0100PA00X+075550Y+023150X0200Y         S0      
317GND              VIA   -    MD0100PA00X+074650Y+023150X0200Y         S0      
317GND              VIA   -    MD0100PA00X+073200Y+023150X0200Y         S0      
317GND              VIA   -    MD0100PA00X+075850Y+023150X0200Y         S0      
317GND              VIA   -    MD0100PA00X+072000Y+023150X0200Y         S0      
317GND              VIA   -    MD0100PA00X+072300Y+023150X0200Y         S0      
317GND              VIA   -    MD0100PA00X+072900Y+023150X0200Y         S0      
317GND              VIA   -    MD0100PA00X+072600Y+023150X0200Y         S0      
317GND              VIA   -    MD0100PA00X+101300Y+023150X0200Y         S0      
317GND              VIA   -    MD0100PA00X+098050Y+023150X0200Y         S0      
317GND              VIA   -    MD0100PA00X+098350Y+023150X0200Y         S0      
317GND              VIA   -    MD0100PA00X+098650Y+023150X0200Y         S0      
317GND              VIA   -    MD0100PA00X+097750Y+023150X0200Y         S0      
317GND              VIA   -    MD0100PA00X+100100Y+023150X0200Y         S0      
317GND              VIA   -    MD0100PA00X+101000Y+023150X0200Y         S0      
317GND              VIA   -    MD0100PA00X+100700Y+023150X0200Y         S0      
317GND              VIA   -    MD0100PA00X+100400Y+023150X0200Y         S0      
317GND              VIA   -    MD0100PA00X+097450Y+023150X0200Y         S0      
317GND              H12   -1   MD1190PA00X+145276Y+005315X3550Y5520R180 S3      
317GND              VIA   -    MD0100PA00X+126634Y+035628X0200Y         S0      
317GND              VIA   -    MD0100PA00X+126634Y+035928X0200Y         S0      
317GND              VIA   -    MD0100PA00X+126334Y+035628X0200Y         S0      
317GND              VIA   -    MD0100PA00X+126334Y+035928X0200Y         S0      
317GND              VIA   -    MD0100PA00X+126034Y+035628X0200Y         S0      
317GND              VIA   -    M      A01X+126034Y+035928X0200Y         S2      
017GND              VIA   -    M      A10X+126034Y+035928X0260Y         S2      
017GND                    -    MD0100PA00X+126034Y+035928                       
317GND              J15   -G1  MD0640PA00X+183574Y+048169X0740Y1230R090 S3      
317GND              J15   -SCR_MD2030PA00X+184858Y+048169X4140Y    R090 S3      
317GND              J16   -G1  MD0640PA00X+183574Y+009921X0740Y1230R090 S3      
317GND              J16   -SCR_MD2030PA00X+184858Y+009921X4140Y    R090 S3      
317GND              JP1   -P2_1MD0295PA00X+158711Y+066468X0455Y         S3      
317GND              JP1   -P2_2MD0295PA00X+158711Y+065681X0455Y         S3      
317GND              JP1   -P2_3MD0295PA00X+158711Y+064894X0455Y         S3      
317GND              JP1   -P2_1MD0295PA00X+159498Y+066468X0455Y         S3      
317GND              JP1   -P2_1MD0295PA00X+159498Y+065681X0455Y         S3      
317GND              JP1   -P2_1MD0295PA00X+159498Y+064894X0455Y         S3      
317GND              J1    -D1  MD0295PA00X+154016Y+064894X0455Y    R180 S3      
317GND              J1    -D2  MD0295PA00X+154016Y+065681X0455Y    R180 S3      
317GND              J1    -D3  MD0295PA00X+154016Y+066468X0455Y    R180 S3      
317GND              J1    -D4  MD0295PA00X+153228Y+064894X0455Y    R180 S3      
317GND              J1    -D5  MD0295PA00X+153228Y+065681X0455Y    R180 S3      
317GND              J1    -D6  MD0295PA00X+153228Y+066468X0455Y    R180 S3      
317GND              J1    -C4  MD0295PA00X+151654Y+064894X0455Y    R180 S3      
317GND              J1    -C5  MD0295PA00X+151654Y+065681X0455Y    R180 S3      
317GND              J1    -C6  MD0295PA00X+151654Y+066468X0455Y    R180 S3      
317GND              J1    -C1  MD0295PA00X+150866Y+064894X0455Y    R180 S3      
317GND              J1    -C2  MD0295PA00X+150866Y+065681X0455Y    R180 S3      
317GND              J1    -C3  MD0295PA00X+150866Y+066468X0455Y    R180 S3      
317GND              J2    -F5  MD0295PA00X+147638Y+065681X0455Y    R180 S3      
317GND              J2    -F4  MD0295PA00X+147638Y+066468X0455Y    R180 S3      
317GND              J2    -F3  MD0295PA00X+148425Y+066468X0455Y    R180 S3      
317GND              J2    -F2  MD0295PA00X+148425Y+065681X0455Y    R180 S3      
317GND              J2    -F6  MD0295PA00X+147638Y+064894X0455Y    R180 S3      
317GND              J2    -F1  MD0295PA00X+148425Y+064894X0455Y    R180 S3      
317GND              J2    -E5  MD0295PA00X+145276Y+065681X0455Y    R180 S3      
317GND              J2    -E4  MD0295PA00X+145276Y+066468X0455Y    R180 S3      
317GND              J2    -E3  MD0295PA00X+146063Y+066468X0455Y    R180 S3      
317GND              J2    -E2  MD0295PA00X+146063Y+065681X0455Y    R180 S3      
317GND              J2    -E6  MD0295PA00X+145276Y+064894X0455Y    R180 S3      
317GND              J2    -E1  MD0295PA00X+146063Y+064894X0455Y    R180 S3      
317GND              J2    -D5  MD0295PA00X+142913Y+065681X0455Y    R180 S3      
317GND              J2    -D4  MD0295PA00X+142913Y+066468X0455Y    R180 S3      
317GND              J2    -D3  MD0295PA00X+143701Y+066468X0455Y    R180 S3      
317GND              J2    -D2  MD0295PA00X+143701Y+065681X0455Y    R180 S3      
317GND              J2    -D6  MD0295PA00X+142913Y+064894X0455Y    R180 S3      
317GND              J2    -D1  MD0295PA00X+143701Y+064894X0455Y    R180 S3      
317GND              J4    -F5  MD0295PA00X+029528Y+065681X0455Y    R180 S3      
317GND              J4    -F4  MD0295PA00X+029528Y+066468X0455Y    R180 S3      
317GND              J4    -F3  MD0295PA00X+030315Y+066468X0455Y    R180 S3      
317GND              J4    -F2  MD0295PA00X+030315Y+065681X0455Y    R180 S3      
317GND              J4    -F6  MD0295PA00X+029528Y+064894X0455Y    R180 S3      
317GND              J4    -F1  MD0295PA00X+030315Y+064894X0455Y    R180 S3      
317GND              J4    -E5  MD0295PA00X+027165Y+065681X0455Y    R180 S3      
317GND              J4    -E4  MD0295PA00X+027165Y+066468X0455Y    R180 S3      
317GND              J4    -E3  MD0295PA00X+027953Y+066468X0455Y    R180 S3      
317GND              J4    -E2  MD0295PA00X+027953Y+065681X0455Y    R180 S3      
317GND              J4    -E6  MD0295PA00X+027165Y+064894X0455Y    R180 S3      
317GND              J4    -E1  MD0295PA00X+027953Y+064894X0455Y    R180 S3      
317GND              J4    -D5  MD0295PA00X+024803Y+065681X0455Y    R180 S3      
317GND              J4    -D4  MD0295PA00X+024803Y+066468X0455Y    R180 S3      
317GND              J4    -D3  MD0295PA00X+025591Y+066468X0455Y    R180 S3      
317GND              J4    -D2  MD0295PA00X+025591Y+065681X0455Y    R180 S3      
317GND              J4    -D6  MD0295PA00X+024803Y+064894X0455Y    R180 S3      
317GND              J4    -D1  MD0295PA00X+025591Y+064894X0455Y    R180 S3      
317GND              J3    -C4  MD0295PA00X+020000Y+064894X0455Y    R180 S3      
317GND              J3    -C5  MD0295PA00X+020000Y+065681X0455Y    R180 S3      
317GND              J3    -C6  MD0295PA00X+020000Y+066468X0455Y    R180 S3      
317GND              J3    -C1  MD0295PA00X+019213Y+064894X0455Y    R180 S3      
317GND              J3    -C2  MD0295PA00X+019213Y+065681X0455Y    R180 S3      
317GND              J3    -C3  MD0295PA00X+019213Y+066468X0455Y    R180 S3      
317GND              J3    -D1  MD0295PA00X+022362Y+064894X0455Y    R180 S3      
317GND              J3    -D2  MD0295PA00X+022362Y+065681X0455Y    R180 S3      
317GND              J3    -D3  MD0295PA00X+022362Y+066468X0455Y    R180 S3      
317GND              J3    -D4  MD0295PA00X+021575Y+064894X0455Y    R180 S3      
317GND              J3    -D5  MD0295PA00X+021575Y+065681X0455Y    R180 S3      
317GND              J3    -D6  MD0295PA00X+021575Y+066468X0455Y    R180 S3      
317GND              JP2   -P2_1MD0295PA00X+015600Y+066468X0455Y         S3      
317GND              JP2   -P2_2MD0295PA00X+015600Y+065681X0455Y         S3      
317GND              JP2   -P2_3MD0295PA00X+015600Y+064894X0455Y         S3      
317GND              JP2   -P2_1MD0295PA00X+016388Y+066468X0455Y         S3      
317GND              JP2   -P2_1MD0295PA00X+016388Y+065681X0455Y         S3      
317GND              JP2   -P2_1MD0295PA00X+016388Y+064894X0455Y         S3      
317GND              JP1   -P2_4MD0295PA00X+158711Y+064106X0455Y         S3      
317GND              JP1   -P2_5MD0295PA00X+158711Y+063319X0455Y         S3      
317GND              JP1   -P2_6MD0295PA00X+158711Y+062532X0455Y         S3      
317GND              JP1   -P2_7MD0295PA00X+158711Y+061744X0455Y         S3      
317GND              JP1   -P2_1MD0295PA00X+159498Y+064106X0455Y         S3      
317GND              JP1   -P2_1MD0295PA00X+159498Y+063319X0455Y         S3      
317GND              JP1   -P2_1MD0295PA00X+159498Y+062532X0455Y         S3      
317GND              JP1   -P2_1MD0295PA00X+159498Y+061744X0455Y         S3      
317GND              JP2   -P2_4MD0295PA00X+015600Y+064106X0455Y         S3      
317GND              JP2   -P2_5MD0295PA00X+015600Y+063319X0455Y         S3      
317GND              JP2   -P2_6MD0295PA00X+015600Y+062532X0455Y         S3      
317GND              JP2   -P2_7MD0295PA00X+015600Y+061744X0455Y         S3      
317GND              JP2   -P2_1MD0295PA00X+016388Y+064106X0455Y         S3      
317GND              JP2   -P2_1MD0295PA00X+016388Y+063319X0455Y         S3      
317GND              JP2   -P2_1MD0295PA00X+016388Y+062532X0455Y         S3      
317GND              JP2   -P2_1MD0295PA00X+016388Y+061744X0455Y         S3      
317GND              JP1   -P2_8MD0295PA00X+158711Y+060957X0455Y         S3      
317GND              JP1   -P2_9MD0295PA00X+158711Y+060169X0455Y         S3      
317GND              JP1   -P2_1MD0295PA00X+159498Y+060957X0455Y         S3      
317GND              JP1   -P2_1MD0295PA00X+159498Y+060169X0455Y         S3      
317GND              JP2   -P2_8MD0295PA00X+015600Y+060957X0455Y         S3      
317GND              JP2   -P2_9MD0295PA00X+015600Y+060169X0455Y         S3      
317GND              JP2   -P2_1MD0295PA00X+016388Y+060957X0455Y         S3      
317GND              JP2   -P2_1MD0295PA00X+016388Y+060169X0455Y         S3      
317GND              H11   -1   MD1190PA00X+141732Y+056102X3550Y5520R180 S3      
317GND              H3    -1   MD1190PA00X+031496Y+056102X3550Y5520R180 S3      
317GND              H15   -1   MD1190PA00X+179921Y+047835X3550Y5520R180 S3      
317GND              H23   -9   MD0220PA00X+168307Y+042146X0300Y         S3      
317GND              H23   -7   MD0220PA00X+168307Y+040177X0300Y         S3      
317GND              H23   -6   MD0220PA00X+167323Y+039783X0300Y         S3      
317GND              H23   -5   MD0220PA00X+166338Y+040177X0300Y         S3      
317GND              H23   -3   MD0220PA00X+166338Y+042146X0300Y         S3      
317GND              H23   -2   MD0220PA00X+167323Y+042539X0300Y         S3      
317GND              H23   -4   MD0220PA00X+165945Y+041161X0300Y         S3      
317GND              H23   -8   MD0220PA00X+168701Y+041161X0300Y         S3      
317GND              VIA   -    MD0100PA00X+037968Y+040251X0200Y         S0      
317GND              VIA   -    MD0100PA00X+039968Y+040251X0200Y         S0      
317GND              VIA   -    MD0100PA00X+043968Y+040251X0200Y         S0      
317GND              VIA   -    MD0100PA00X+041968Y+040251X0200Y         S0      
317GND              VIA   -    MD0100PA00X+047968Y+040251X0200Y         S0      
317GND              VIA   -    MD0100PA00X+045968Y+040251X0200Y         S0      
317GND              VIA   -    MD0100PA00X+051968Y+040251X0200Y         S0      
317GND              VIA   -    MD0100PA00X+049968Y+040251X0200Y         S0      
317GND              VIA   -    MD0100PA00X+055968Y+040251X0200Y         S0      
317GND              VIA   -    MD0100PA00X+053968Y+040251X0200Y         S0      
317GND              VIA   -    MD0100PA00X+059968Y+040251X0200Y         S0      
317GND              VIA   -    MD0100PA00X+057968Y+040251X0200Y         S0      
317GND              VIA   -    MD0100PA00X+063968Y+040251X0200Y         S0      
317GND              VIA   -    MD0100PA00X+061968Y+040251X0200Y         S0      
317GND              VIA   -    MD0100PA00X+067968Y+040251X0200Y         S0      
317GND              VIA   -    MD0100PA00X+065968Y+040251X0200Y         S0      
317GND              VIA   -    MD0100PA00X+071968Y+040251X0200Y         S0      
317GND              VIA   -    MD0100PA00X+069968Y+040251X0200Y         S0      
317GND              VIA   -    MD0100PA00X+075968Y+040251X0200Y         S0      
317GND              VIA   -    MD0100PA00X+073968Y+040251X0200Y         S0      
317GND              VIA   -    MD0100PA00X+079968Y+040251X0200Y         S0      
317GND              VIA   -    MD0100PA00X+077968Y+040251X0200Y         S0      
317GND              VIA   -    MD0100PA00X+081968Y+040251X0200Y         S0      
317GND              VIA   -    MD0100PA00X+085968Y+040251X0200Y         S0      
317GND              VIA   -    MD0100PA00X+083968Y+040251X0200Y         S0      
317GND              VIA   -    MD0100PA00X+089968Y+040251X0200Y         S0      
317GND              VIA   -    MD0100PA00X+087968Y+040251X0200Y         S0      
317GND              VIA   -    MD0100PA00X+093968Y+040251X0200Y         S0      
317GND              VIA   -    MD0100PA00X+091968Y+040251X0200Y         S0      
317GND              VIA   -    MD0100PA00X+097968Y+040251X0200Y         S0      
317GND              VIA   -    MD0100PA00X+095968Y+040251X0200Y         S0      
317GND              VIA   -    MD0100PA00X+101968Y+040251X0200Y         S0      
317GND              VIA   -    MD0100PA00X+099968Y+040251X0200Y         S0      
317GND              VIA   -    MD0100PA00X+105968Y+040251X0200Y         S0      
317GND              VIA   -    MD0100PA00X+103968Y+040251X0200Y         S0      
317GND              VIA   -    MD0100PA00X+109968Y+040251X0200Y         S0      
317GND              VIA   -    MD0100PA00X+107968Y+040251X0200Y         S0      
317GND              VIA   -    MD0100PA00X+113968Y+040251X0200Y         S0      
317GND              VIA   -    MD0100PA00X+111968Y+040251X0200Y         S0      
317GND              VIA   -    MD0100PA00X+117968Y+040251X0200Y         S0      
317GND              VIA   -    MD0100PA00X+115968Y+040251X0200Y         S0      
317GND              VIA   -    MD0100PA00X+121968Y+040251X0200Y         S0      
317GND              VIA   -    MD0100PA00X+119968Y+040251X0200Y         S0      
317GND              VIA   -    MD0100PA00X+123968Y+040251X0200Y         S0      
317GND              VIA   -    MD0100PA00X+127968Y+040251X0200Y         S0      
317GND              VIA   -    MD0100PA00X+125968Y+040251X0200Y         S0      
317GND              VIA   -    MD0100PA00X+131968Y+040251X0200Y         S0      
317GND              VIA   -    MD0100PA00X+129968Y+040251X0200Y         S0      
317GND              VIA   -    MD0100PA00X+135962Y+040294X0200Y         S0      
317GND              VIA   -    MD0100PA00X+133968Y+040251X0200Y         S0      
317GND              H21   -2   MD0220PA00X+005906Y+042537X0300Y         S3      
317GND              H21   -3   MD0220PA00X+004921Y+042144X0300Y         S3      
317GND              H21   -4   MD0220PA00X+004528Y+041159X0300Y         S3      
317GND              H21   -5   MD0220PA00X+004921Y+040175X0300Y         S3      
317GND              H21   -6   MD0220PA00X+005906Y+039781X0300Y         S3      
317GND              H21   -7   MD0220PA00X+006890Y+040175X0300Y         S3      
317GND              H21   -8   MD0220PA00X+007284Y+041159X0300Y         S3      
317GND              H21   -9   MD0220PA00X+006890Y+042144X0300Y         S3      
317GND              H13   -1   MD1190PA00X+168504Y+033071X3550Y5520R180 S3      
317GND              H10   -1   MD1190PA00X+133858Y+034449X3550Y5520R180 S3      
317GND              H8    -1   MD1190PA00X+098425Y+034449X3550Y5520R180 S3      
317GND              H6    -1   MD1190PA00X+074803Y+034449X3550Y5520R180 S3      
317GND              H5    -1   MD1190PA00X+039370Y+034449X3550Y5520R180 S3      
317GND              H1    -1   MD1190PA00X+004724Y+033071X3550Y5520R180 S3      
317GND              H24   -9   MD0220PA00X+168307Y+024646X0300Y         S3      
317GND              H24   -7   MD0220PA00X+168307Y+022677X0300Y         S3      
317GND              H24   -6   MD0220PA00X+167323Y+022283X0300Y         S3      
317GND              H24   -5   MD0220PA00X+166338Y+022677X0300Y         S3      
317GND              H24   -3   MD0220PA00X+166338Y+024646X0300Y         S3      
317GND              H24   -2   MD0220PA00X+167323Y+025039X0300Y         S3      
317GND              H24   -4   MD0220PA00X+165945Y+023661X0300Y         S3      
317GND              H24   -8   MD0220PA00X+168701Y+023661X0300Y         S3      
317GND              VIA   -    MD0100PA00X+046595Y+034122X0200Y    R180 S0      
317GND              VIA   -    MD0100PA00X+046895Y+034122X0200Y    R180 S0      
317GND              VIA   -    M      A01X+047195Y+034122X0200Y    R180 S2      
017GND              VIA   -    M      A10X+047195Y+034122X0260Y    R180 S2      
017GND                    -    MD0100PA00X+047195Y+034122                       
317GND              VIA   -    MD0100PA00X+046595Y+033822X0200Y    R180 S0      
317GND              VIA   -    MD0100PA00X+046895Y+033822X0200Y    R180 S0      
317GND              VIA   -    MD0100PA00X+047195Y+033822X0200Y    R180 S0      
317GND              JP5   -3   MD0460PA00X+090690Y+038220X0660Y    R090 S3      
317GND              JP6   -3   MD0460PA00X+082590Y+038220X0660Y    R090 S3      
317GND              J6    -P3_1MD0402PA00X+091020Y+022098X0602Y    R180 S3      
317GND              J6    -P3_4MD0402PA00X+094020Y+022098X0602Y    R180 S3      
317GND              J6    -P3_3MD0402PA00X+093020Y+022098X0602Y    R180 S3      
317GND              J6    -P3_2MD0402PA00X+092020Y+022098X0602Y    R180 S3      
317GND              J6    -P4_5MD0402PA00X+091020Y+026598X0602Y    R180 S3      
317GND              J6    -P4_1MD0402PA00X+091020Y+025598X0602Y    R180 S3      
317GND              J6    -P3_5MD0402PA00X+091020Y+023098X0602Y    R180 S3      
317GND              J6    -P4_8MD0402PA00X+094020Y+026598X0602Y    R180 S3      
317GND              J6    -P4_7MD0402PA00X+093020Y+026598X0602Y    R180 S3      
317GND              J6    -P4_6MD0402PA00X+092020Y+026598X0602Y    R180 S3      
317GND              J6    -P4_4MD0402PA00X+094020Y+025598X0602Y    R180 S3      
317GND              J6    -P4_3MD0402PA00X+093020Y+025598X0602Y    R180 S3      
317GND              J6    -P4_2MD0402PA00X+092020Y+025598X0602Y    R180 S3      
317GND              J6    -P3_8MD0402PA00X+094020Y+023098X0602Y    R180 S3      
317GND              J6    -P3_7MD0402PA00X+093020Y+023098X0602Y    R180 S3      
317GND              J6    -P3_6MD0402PA00X+092020Y+023098X0602Y    R180 S3      
317GND              J7    -P3_1MD0402PA00X+079209Y+022098X0602Y    R180 S3      
317GND              J7    -P3_4MD0402PA00X+082209Y+022098X0602Y    R180 S3      
317GND              J7    -P3_3MD0402PA00X+081209Y+022098X0602Y    R180 S3      
317GND              J7    -P3_2MD0402PA00X+080209Y+022098X0602Y    R180 S3      
317GND              J7    -P4_5MD0402PA00X+079209Y+026598X0602Y    R180 S3      
317GND              J7    -P4_1MD0402PA00X+079209Y+025598X0602Y    R180 S3      
317GND              J7    -P3_5MD0402PA00X+079209Y+023098X0602Y    R180 S3      
317GND              J7    -P4_8MD0402PA00X+082209Y+026598X0602Y    R180 S3      
317GND              J7    -P4_7MD0402PA00X+081209Y+026598X0602Y    R180 S3      
317GND              J7    -P4_6MD0402PA00X+080209Y+026598X0602Y    R180 S3      
317GND              J7    -P4_4MD0402PA00X+082209Y+025598X0602Y    R180 S3      
317GND              J7    -P4_3MD0402PA00X+081209Y+025598X0602Y    R180 S3      
317GND              J7    -P4_2MD0402PA00X+080209Y+025598X0602Y    R180 S3      
317GND              J7    -P3_8MD0402PA00X+082209Y+023098X0602Y    R180 S3      
317GND              J7    -P3_7MD0402PA00X+081209Y+023098X0602Y    R180 S3      
317GND              J7    -P3_6MD0402PA00X+080209Y+023098X0602Y    R180 S3      
317GND              H22   -8   MD0220PA00X+007284Y+023661X0300Y         S3      
317GND              H22   -4   MD0220PA00X+004528Y+023661X0300Y         S3      
317GND              H22   -2   MD0220PA00X+005906Y+025039X0300Y         S3      
317GND              H22   -3   MD0220PA00X+004921Y+024646X0300Y         S3      
317GND              H22   -5   MD0220PA00X+004921Y+022677X0300Y         S3      
317GND              H22   -6   MD0220PA00X+005906Y+022283X0300Y         S3      
317GND              H22   -7   MD0220PA00X+006890Y+022677X0300Y         S3      
317GND              H22   -9   MD0220PA00X+006890Y+024646X0300Y         S3      
317GND              VIA   -    MD0100PA00X+159493Y+011500X0200Y         S0      
327GND              D1    -C          A01X+159763Y+011500X0240Y0280R180 S1      
317GND              H16   -1   MD1190PA00X+179921Y+009646X3550Y5520R180 S3      
317GND              H9    -1   MD1190PA00X+098425Y+006496X3550Y5520R180 S3      
317GND              H7    -1   MD1190PA00X+074803Y+006496X3550Y5520R180 S3      
317GND              H4    -1   MD1190PA00X+027953Y+005315X3550Y5520R180 S3      
317GND              H14   -1   MD1190PA00X+168504Y+001772X3550Y5520R180 S3      
317GND              J8    -P3  MD0295PA00X+145142Y+002083X0455Y    R270 S3      
317GND              J8    -S6  MD0295PA00X+147520Y+001801X0455Y    R270 S3      
317GND              J8    -P4  MD0295PA00X+144142Y+002083X0455Y    R270 S3      
317GND              J9    -S6  MD0295PA00X+028465Y+001801X0455Y    R270 S3      
317GND              J9    -P4  MD0295PA00X+025087Y+002083X0455Y    R270 S3      
317GND              J9    -P3  MD0295PA00X+026087Y+002083X0455Y    R270 S3      
317GND              H2    -1   MD1190PA00X+004724Y+001772X3550Y5520R180 S3      
317GND              VIA   -    M      A01X+013736Y+012050X0200Y         S2      
017GND              VIA   -    M      A10X+013736Y+012050X0260Y         S2      
017GND                    -    MD0100PA00X+013736Y+012050                       
327GND              D2    -C          A01X+013466Y+012050X0240Y0280     S1      
317GND              VIA   -    M      A01X+020506Y+006750X0200Y         S2      
017GND              VIA   -    M      A10X+020506Y+006750X0260Y         S2      
017GND                    -    MD0100PA00X+020506Y+006750                       
317GND              VIA   -    MD0100PA00X+020506Y+007150X0200Y         S0      
317GND              VIA   -    MD0100PA00X+020506Y+007500X0200Y         S0      
317GND              VIA   -    MD0100PA00X+020506Y+007900X0200Y         S0      
317GND              VIA   -    MD0100PA00X+020506Y+009700X0200Y         S0      
317GND              VIA   -    M      A01X+020506Y+009300X0200Y         S2      
017GND              VIA   -    M      A10X+020506Y+009300X0260Y         S2      
017GND                    -    MD0100PA00X+020506Y+009300                       
317GND              VIA   -    MD0100PA00X+020506Y+008950X0200Y         S0      
317GND              VIA   -    MD0100PA00X+020506Y+008550X0200Y         S0      
317GND              VIA   -    M      A01X+168510Y+012750X0200Y    R180 S2      
017GND              VIA   -    M      A10X+168510Y+012750X0260Y    R180 S2      
017GND                    -    MD0100PA00X+168510Y+012750                       
327GND              C9    -1          A01X+168510Y+012498X0198Y0197R270 S1      
327GND              C8    -2          A01X+166808Y+018650X0198Y0197     S1      
317GND              VIA   -    M      A01X+166808Y+018950X0200Y         S2      
017GND              VIA   -    M      A10X+166808Y+018950X0260Y         S2      
017GND                    -    MD0100PA00X+166808Y+018950                       
317GND              VIA   -    M      A01X+176708Y+015548X0200Y         S2      
017GND              VIA   -    M      A10X+176708Y+015548X0260Y         S2      
017GND                    -    MD0100PA00X+176708Y+015548                       
327GND              C2    -2          A01X+176708Y+015300X0198Y0197     S1      
327GND              C26   -1          A01X+176308Y+018150X0198Y0197R180 S1      
317GND              VIA   -    M      A01X+176308Y+017890X0200Y         S2      
017GND              VIA   -    M      A10X+176308Y+017890X0260Y         S2      
017GND                    -    MD0100PA00X+176308Y+017890                       
327GND              C3    -2          A01X+177058Y+013450X0198Y0197     S1      
317GND              VIA   -    M      A01X+177058Y+013700X0200Y    R270 S2      
017GND              VIA   -    M      A10X+177058Y+013700X0260Y    R270 S2      
017GND                    -    MD0100PA00X+177058Y+013700                       
327GND              U24   -S   M      A01X+103694Y+020524X0320Y0360R090 S1      
327GND              U25   -S          A01X+069716Y+018976X0320Y0360R270 S1      
327GND              R155  -2          A01X+103760Y+019208X0198Y0197R090 S1      
327GND              U22   -S   M      A01X+104336Y+019744X0320Y0360R180 S1      
327GND              C101  -2          A10X+164528Y+012740X0198Y0197R090 S2      
317FRU_ADDR1        VIA   -    M      A01X+172168Y+009594X0200Y    R180 S2      
017FRU_ADDR1        VIA   -    M      A10X+172168Y+009594X0260Y    R180 S2      
017FRU_ADDR1              -    MD0100PA00X+172168Y+009594                       
327FRU_ADDR1        R60   -2   M      A01X+171312Y+009350X0198Y0197R180 S1      
327FRU_ADDR1        R65   -2          A01X+172412Y+009350X0198Y0197R180 S1      
327FRU_ADDR1        U9    -2          A01X+169610Y+008650X0220Y0680     S1      
327FRU_ADDR0        VIA   -    M      A01X+171410Y+010450X0300Y         S1      
327FRU_ADDR0        R66   -2          A01X+172412Y+009900X0198Y0197R180 S1      
327FRU_ADDR0        R61   -2   M      A01X+171312Y+009900X0198Y0197R180 S1      
327FRU_ADDR0        U9    -1          A01X+169110Y+008650X0220Y0680     S1      
317m0133            J13   -2    D0670PA00X+068160Y+059319X0850Y    R270 S3      
317m0133            J13   -3    D0670PA00X+068160Y+060319X0850Y    R270 S3      
317m0134            J14   -3    D0670PA00X+099783Y+056504X0850Y    R090 S3      
317m0134            J14   -2    D0670PA00X+099783Y+057504X0850Y    R090 S3      
317GND3             J10   -1   MD0670PA00X+101102Y+059819X0850Y    R090 S3      
317GND3             J13   -1   MD0670PA00X+066842Y+059819X0850Y    R270 S3      
317GND3             J14   -1   MD0670PA00X+101102Y+057004X0850Y    R090 S3      
317GND3             J12   -1   MD0670PA00X+066831Y+057004X0850Y    R270 S3      
317m0135            J10   -2    D0670PA00X+099783Y+059319X0850Y    R090 S3      
317m0135            J10   -3    D0670PA00X+099783Y+060319X0850Y    R090 S3      
317m0136            J12   -2    D0670PA00X+068150Y+057504X0850Y    R270 S3      
317m0136            J12   -3    D0670PA00X+068150Y+056504X0850Y    R270 S3      
317P3V3_AUX         VIA   -    M      A01X+097860Y+031096X0200Y         S2      
017P3V3_AUX         VIA   -    M      A10X+097860Y+031096X0260Y         S2      
017P3V3_AUX               -    MD0100PA00X+097860Y+031096                       
327P3V3_AUX         R146  -1          A10X+109768Y+026750X0198Y0197     S2      
317P3V3_AUX         VIA   -    MD0100PA00X+110050Y+026350X0200Y         S0      
327P3V3_AUX         R147  -1   M      A10X+109768Y+026350X0198Y0197     S2      
327P3V3_AUX         R150  -1          A10X+109768Y+024350X0198Y0197     S2      
317P3V3_AUX         VIA   -    MD0100PA00X+110010Y+024350X0200Y         S0      
327P3V3_AUX         R357  -1          A01X+108568Y+025150X0198Y0197R180 S1      
327P3V3_AUX         C107  -2   M      A01X+073200Y+030742X0198Y0197R270 S1      
327P3V3_AUX         U45   -5          A01X+072556Y+030526X0170Y0240R180 S1      
317P3V3_AUX         VIA   -    MD0100PA00X+073450Y+030742X0200Y         S0      
327P3V3_AUX         R5945 -1          A01X+073039Y+030060X0198Y0197R180 S1      
317P3V3_AUX         VIA   -    MD0100PA00X+066212Y+030850X0200Y         S0      
327P3V3_AUX         R5889 -1          A10X+066452Y+030850X0198Y0197R180 S2      
317P3V3_AUX         VIA   -    M      A01X+067510Y+030450X0200Y         S2      
017P3V3_AUX         VIA   -    M      A10X+067510Y+030450X0260Y         S2      
017P3V3_AUX               -    MD0100PA00X+067510Y+030450                       
327P3V3_AUX         R5887 -1          A01X+067752Y+030250X0198Y0197     S1      
327P3V3_AUX         R5944 -1          A01X+066208Y+032250X0198Y0197R180 S1      
317P3V3_AUX         VIA   -    MD0100PA00X+066208Y+032000X0200Y         S0      
317P3V3_AUX         VIA   -    MD0100PA00X+065750Y+033008X0200Y         S0      
327P3V3_AUX         C106  -2   M      A01X+065350Y+033008X0198Y0197R090 S1      
327P3V3_AUX         U44   -5          A01X+064394Y+032474X0170Y0240     S1      
317P3V3_AUX         VIA   -    MD0100PA00X+066218Y+028450X0200Y    R180 S0      
327P3V3_AUX         R5884 -1          A10X+066461Y+028450X0198Y0197R180 S2      
317P3V3_AUX         VIA   -    MD0100PA00X+066218Y+028850X0200Y    R180 S0      
327P3V3_AUX         R5885 -1          A10X+066461Y+028850X0198Y0197R180 S2      
327P3V3_AUX         PC54  -2   M      A01X+177982Y+033650X0198Y0197R270 S1      
327P3V3_AUX         PR112 -2          A01X+177582Y+033650X0198Y0197R270 S1      
317P3V3_AUX         VIA   -    MD0100PA00X+177738Y+035630X0200Y    R270 S0      
327P3V3_AUX         PR110 -1          A01X+177498Y+035630X0198Y0197R180 S1      
317P3V3_AUX         VIA   -    MD0100PA00X+176643Y+024730X0200Y         S0      
317P3V3_AUX         VIA   -    MD0100PA00X+176643Y+025030X0200Y         S0      
317P3V3_AUX         VIA   -    MD0100PA00X+177543Y+024736X0200Y         S0      
317P3V3_AUX         VIA   -    MD0100PA00X+177543Y+025036X0200Y         S0      
317P3V3_AUX         VIA   -    MD0100PA00X+178393Y+024736X0200Y         S0      
317P3V3_AUX         VIA   -    MD0100PA00X+178393Y+025036X0200Y         S0      
317P3V3_AUX         VIA   -    MD0100PA00X+175160Y+024800X0200Y         S0      
317P3V3_AUX         VIA   -    MD0100PA00X+175160Y+025050X0200Y         S0      
317P3V3_AUX         VIA   -    MD0100PA00X+175160Y+025300X0200Y         S0      
317P3V3_AUX         VIA   -    MD0100PA00X+174060Y+025300X0200Y         S0      
317P3V3_AUX         VIA   -    MD0100PA00X+174060Y+025050X0200Y         S0      
317P3V3_AUX         VIA   -    MD0100PA00X+174060Y+024800X0200Y         S0      
317P3V3_AUX         VIA   -    MD0100PA00X+178960Y+024700X0200Y         S0      
327P3V3_AUX         PC51  -1          A01X+178660Y+024658X0198Y0197R270 S1      
327P3V3_AUX         PC48  -1          A01X+177960Y+024850X0400Y0500R090 S1      
327P3V3_AUX         PC50  -1          A01X+176210Y+024850X0400Y0500R090 S1      
327P3V3_AUX         PC137 -1          A01X+174610Y+025316X0630Y1190     S1      
327P3V3_AUX         PL2   -2          A01X+175988Y+026772X1280Y1380R270 S1      
327P3V3_AUX         PC49  -1          A01X+177110Y+024850X0400Y0500R090 S1      
317P3V3_AUX         VIA   -    MD0100PA00X+174060Y+025550X0200Y         S0      
317P3V3_AUX         VIA   -    MD0100PA00X+174060Y+025800X0200Y         S0      
317P3V3_AUX         VIA   -    MD0100PA00X+175160Y+025550X0200Y         S0      
317P3V3_AUX         VIA   -    MD0100PA00X+175160Y+025800X0200Y         S0      
327P3V3_AUX         R5929 -1          A01X+173208Y+025000X0198Y0197R180 S1      
317P3V3_AUX         VIA   -    MD0100PA00X+175492Y+020300X0200Y         S0      
327P3V3_AUX         R5913 -1          A01X+175492Y+020050X0198Y0197     S1      
317P3V3_AUX         VIA   -    MD0100PA00X+176942Y+020300X0200Y         S0      
327P3V3_AUX         R5914 -1          A01X+176942Y+020050X0198Y0197     S1      
317P3V3_AUX         VIA   -    MD0100PA00X+176692Y+018150X0200Y         S0      
327P3V3_AUX         U40   -5          A10X+175882Y+018376X0220Y0320R270 S2      
327P3V3_AUX         C103  -1   M      A10X+176692Y+018400X0198Y0197R180 S2      
317P3V3_AUX         VIA   -    MD0100PA00X+171418Y+018700X0200Y         S0      
327P3V3_AUX         U33   -5          A01X+171538Y+019476X0220Y0320R090 S1      
327P3V3_AUX         C89   -1   M      A01X+171418Y+018950X0198Y0197R180 S1      
317P3V3_AUX         VIA   -    MD0100PA00X+173192Y+019900X0200Y         S0      
327P3V3_AUX         R386  -2          A01X+173192Y+020150X0198Y0197R180 S1      
327P3V3_AUX         R5912 -1          A01X+161242Y+016550X0198Y0197     S1      
327P3V3_AUX         R5911 -1   M      A01X+161242Y+016950X0198Y0197     S1      
327P3V3_AUX         R52   -1   M      A01X+161850Y+018558X0198Y0197R270 S1      
327P3V3_AUX         R51   -1   M      A01X+161242Y+017300X0198Y0197     S1      
327P3V3_AUX         R48   -1   M      A01X+162642Y+018300X0198Y0197     S1      
317P3V3_AUX         VIA   -    MD0100PA00X+170460Y+020150X0200Y         S0      
327P3V3_AUX         C8    -1   M      A01X+166492Y+018650X0198Y0197     S1      
327P3V3_AUX         U8    -24         A01X+166650Y+018108X0140Y0590R270 S1      
327P3V3_AUX         R53   -1          A01X+169558Y+018100X0198Y0197R180 S1      
317P3V3_AUX         VIA   -    MD0100PA00X+169798Y+018100X0200Y         S0      
327P3V3_AUX         U2    -8          A01X+175129Y+015134X0140Y0560R270 S1      
327P3V3_AUX         C2    -1   M      A01X+176392Y+015300X0198Y0197     S1      
317P3V3_AUX         VIA   -    MD0100PA00X+176392Y+015548X0200Y         S0      
327P3V3_AUX         C1    -1   M      A01X+176392Y+016850X0198Y0197     S1      
317P3V3_AUX         VIA   -    MD0100PA00X+176392Y+017098X0200Y         S0      
327P3V3_AUX         U1    -8          A01X+175129Y+016684X0140Y0560R270 S1      
317P3V3_AUX         VIA   -    MD0100PA00X+176850Y+015802X0200Y         S0      
327P3V3_AUX         R2    -2          A01X+176850Y+016042X0198Y0197R270 S1      
327P3V3_AUX         C26   -2   M      A01X+175992Y+018150X0198Y0197R180 S1      
327P3V3_AUX         U21   -5          A01X+174732Y+018124X0180Y0520R270 S1      
317P3V3_AUX         VIA   -    MD0100PA00X+175992Y+017890X0200Y         S0      
317P3V3_AUX         VIA   -    MD0100PA00X+171760Y+015800X0200Y         S0      
327P3V3_AUX         R1    -2          A01X+171650Y+016042X0198Y0197R270 S1      
327P3V3_AUX         R381  -2          A01X+172292Y+017500X0198Y0197R180 S1      
317P3V3_AUX         VIA   -    MD0100PA00X+172052Y+017500X0200Y         S0      
327P3V3_AUX         R5936 -1          A10X+168108Y+015350X0198Y0197     S2      
317P3V3_AUX         VIA   -    MD0100PA00X+168000Y+015650X0200Y         S0      
317P3V3_AUX         VIA   -    MD0100PA00X+169798Y+015350X0200Y         S0      
327P3V3_AUX         R134  -1          A01X+169558Y+015350X0198Y0197R180 S1      
327P3V3_AUX         R97   -1          A01X+169558Y+017000X0198Y0197R180 S1      
317P3V3_AUX         VIA   -    MD0100PA00X+169798Y+017000X0200Y         S0      
327P3V3_AUX         R96   -1          A01X+169558Y+017550X0198Y0197R180 S1      
317P3V3_AUX         VIA   -    MD0100PA00X+169798Y+017550X0200Y         S0      
327P3V3_AUX         R133  -1          A01X+169558Y+015900X0198Y0197R180 S1      
317P3V3_AUX         VIA   -    MD0100PA00X+169798Y+015900X0200Y         S0      
327P3V3_AUX         R98   -1          A01X+169558Y+016450X0198Y0197R180 S1      
317P3V3_AUX         VIA   -    MD0100PA00X+169798Y+016450X0200Y         S0      
327P3V3_AUX         R9    -2          A01X+176850Y+014492X0198Y0197R270 S1      
317P3V3_AUX         VIA   -    MD0100PA00X+176850Y+014252X0200Y         S0      
327P3V3_AUX         U18   -14         A01X+175290Y+013450X0220Y0680R270 S1      
327P3V3_AUX         C3    -1   M      A01X+176742Y+013450X0198Y0197     S1      
317P3V3_AUX         VIA   -    MD0100PA00X+176742Y+013700X0200Y    R270 S0      
317P3V3_AUX         VIA   -    MD0100PA00X+171352Y+011950X0200Y    R270 S0      
327P3V3_AUX         R15   -2          A01X+171592Y+011950X0198Y0197R180 S1      
327P3V3_AUX         R22   -1          A01X+171592Y+012950X0198Y0197     S1      
317P3V3_AUX         VIA   -    MD0100PA00X+171352Y+012950X0200Y         S0      
327P3V3_AUX         R8    -2          A01X+171710Y+014492X0198Y0197R270 S1      
327P3V3_AUX         R23   -1          A01X+171592Y+013450X0198Y0197     S1      
317P3V3_AUX         VIA   -    MD0100PA00X+171352Y+013450X0200Y         S0      
317P3V3_AUX         VIA   -    MD0100PA00X+169010Y+012738X0200Y    R180 S0      
327P3V3_AUX         R57   -1          A01X+169010Y+012498X0198Y0197R270 S1      
317P3V3_AUX         VIA   -    MD0100PA00X+169798Y+014800X0200Y         S0      
327P3V3_AUX         R135  -1          A01X+169558Y+014800X0198Y0197R180 S1      
327P3V3_AUX         R330  -2          A01X+177068Y+011650X0198Y0197     S1      
317P3V3_AUX         VIA   -    MD0100PA00X+177308Y+011750X0200Y         S0      
317P3V3_AUX         VIA   -    MD0100PA00X+177298Y+010450X0200Y         S0      
327P3V3_AUX         R16   -2          A01X+177058Y+010450X0198Y0197     S1      
317P3V3_AUX         VIA   -    MD0100PA00X+177298Y+010950X0200Y         S0      
327P3V3_AUX         R331  -2          A01X+177058Y+010950X0198Y0197     S1      
317P3V3_AUX         VIA   -    MD0100PA00X+171352Y+011450X0200Y    R270 S0      
327P3V3_AUX         R329  -2          A01X+171592Y+011450X0198Y0197R180 S1      
317P3V3_AUX         VIA   -    MD0100PA00X+171352Y+010950X0200Y    R270 S0      
327P3V3_AUX         R328  -2          A01X+171592Y+010950X0198Y0197R180 S1      
327P3V3_AUX         R60   -1          A01X+171628Y+009350X0198Y0197R180 S1      
317P3V3_AUX         VIA   -    MD0100PA00X+171868Y+009350X0200Y    R270 S0      
327P3V3_AUX         R61   -1          A01X+171628Y+009900X0198Y0197R180 S1      
317P3V3_AUX         VIA   -    MD0100PA00X+171868Y+009900X0200Y    R270 S0      
327P3V3_AUX         R59   -1          A01X+171628Y+008800X0198Y0197R180 S1      
317P3V3_AUX         VIA   -    MD0100PA00X+171868Y+008800X0200Y    R270 S0      
317P3V3_AUX         J8    -S4   D0295PA00X+148020Y+001301X0455Y    R270 S3      
317P3V3_AUX         J9    -S4   D0295PA00X+028965Y+001301X0455Y    R270 S3      
327P3V3_AUX         R5916 -1          A01X+162470Y+011514X0198Y0197     S1      
327P3V3_AUX         R5922 -2          A01X+162470Y+011914X0198Y0197R180 S1      
317P3V3_AUX         VIA   -    MD0100PA00X+162230Y+011894X0200Y         S0      
317P3V3_AUX         VIA   -    MD0100PA00X+162230Y+011494X0200Y         S0      
317P3V3_AUX         VIA   -    MD0100PA00X+161410Y+012500X0200Y         S0      
327P3V3_AUX         C9    -2   M      A01X+168510Y+012182X0198Y0197R270 S1      
317P3V3_AUX         VIA   -    MD0100PA00X+168250Y+012182X0200Y    R180 S0      
327P3V3_AUX         U9    -8          A01X+169110Y+010730X0220Y0680     S1      
327P3V3_AUX         R5934 -1          A10X+162692Y+014600X0198Y0197R180 S2      
317P3V3_AUX         VIA   -    MD0100PA00X+162450Y+014600X0200Y         S0      
327P3V3_AUX         R5935 -1          A10X+162692Y+014250X0198Y0197R180 S2      
317P3V3_AUX         VIA   -    MD0100PA00X+162450Y+014250X0200Y         S0      
327P3V3_AUX         C102  -1   M      A10X+166102Y+013800X0198Y0197R180 S2      
317P3V3_AUX         VIA   -    MD0100PA00X+165850Y+013800X0200Y         S0      
327P3V3_AUX         R5931 -1          A10X+165558Y+013800X0198Y0197     S2      
327P3V3_AUX         U39   -24         A10X+166650Y+014525X0140Y0590R270 S2      
317P3V3_AUX         VIA   -    MD0100PA00X+116820Y+034970X0200Y         S0      
327P3V3_AUX         R5942 -1          A10X+116300Y+034758X0198Y0197R090 S2      
317P3V3_AUX         VIA   -    MD0100PA00X+116242Y+034050X0200Y         S0      
327P3V3_AUX         U42   -5          A10X+115774Y+033794X0170Y0240R270 S2      
327P3V3_AUX         C104  -2   M      A10X+116242Y+033800X0198Y0197     S2      
327P3V3_AUX         C105  -2   M      A10X+117050Y+035658X0198Y0197R270 S2      
327P3V3_AUX         U43   -5          A10X+117094Y+036126X0170Y0240R180 S2      
317P3V3_AUX         VIA   -    MD0100PA00X+116780Y+035500X0200Y         S0      
327P3V3_AUX         R5943 -1          A10X+117600Y+035342X0198Y0197R270 S2      
317P3V3_AUX         VIA   -    M      A01X+117600Y+035000X0200Y         S2      
017P3V3_AUX         VIA   -    M      A10X+117600Y+035000X0260Y         S2      
017P3V3_AUX               -    MD0100PA00X+117600Y+035000                       
317P52V_HS1         VIA   -    MD0100PA00X+110366Y+030770X0200Y         S0      
317P52V_HS1         VIA   -    MD0100PA00X+110666Y+030770X0200Y         S0      
327P52V_HS1         PR19  -1          A10X+110434Y+031200X0440Y0540R180 S2      
327P52V_HS1         PR23  -1          A10X+117434Y+031200X0440Y0540R180 S2      
327P52V_HS1         PR25  -1          A10X+117434Y+030300X0440Y0540R180 S2      
317P52V_HS1         VIA   -    MD0100PA00X+117320Y+031650X0200Y    R090 S0      
317P52V_HS1         VIA   -    MD0100PA00X+117620Y+031650X0200Y    R090 S0      
317P52V_HS1         VIA   -    MD0100PA00X+117350Y+029850X0200Y    R090 S0      
327P52V_HS1         PU1   -1          A10X+116909Y+028683X0110Y0280R090 S2      
327P52V_HS1         PU7   -31         A10X+104805Y+027498X0120Y0330R090 S2      
327P52V_HS1         PC588 -1          A10X+103310Y+027780X0460Y0620R270 S2      
317P52V_HS1         VIA   -    MD0100PA00X+102950Y+028180X0200Y         S0      
317P52V_HS1         VIA   -    MD0100PA00X+103250Y+028180X0200Y         S0      
327P52V_HS1         R148  -1          A10X+107210Y+023176X0440Y0540R090 S2      
327P52V_HS1         PR17  -1          A10X+106310Y+023176X0440Y0540R090 S2      
317P52V_HS1         VIA   -    MD0100PA00X+107060Y+022800X0200Y         S0      
317P52V_HS1         VIA   -    MD0100PA00X+107360Y+022800X0200Y         S0      
317P52V_HS1         VIA   -    MD0100PA00X+106460Y+022800X0200Y         S0      
317P52V_HS1         VIA   -    MD0100PA00X+106160Y+022800X0200Y         S0      
327P52V_HS1         PQ32  -S          A01X+129995Y+030390X0520Y1220R090 S1      
327P52V_HS1         PQ33  -S          A01X+129995Y+025950X0520Y1220R090 S1      
327P52V_HS1         PQ34  -S          A01X+129995Y+021510X0520Y1220R090 S1      
327P52V_HS1         R160  -1          A01X+162136Y+020250X0440Y0540R180 S1      
327P52V_HS1         R38   -1          A01X+159270Y+015800X0400Y0630     S1      
327P52V_HS1         PQ6   -S          A01X+129995Y+017070X0520Y1220R090 S1      
327P52V_HS1         PQ15  -D          A01X+156550Y+014047X3327Y4173R090 S1      
327P52V_HS1         PR98  -1          A01X+153960Y+013630X0400Y0630R270 S1      
327P52V_HS1         PD8   -C          A01X+150160Y+013639X0990Y1300R270 S1      
327P52V_HS1         PQ35  -S          A01X+129995Y+012630X0520Y1220R090 S1      
327P52V_HS1         PQ36  -S          A01X+129995Y+008190X0520Y1220R090 S1      
327P52V_HS1         PC584 -2          A10X+135540Y+019400X0280Y0320R270 S2      
327P52V_HS1         PC82  -2          A10X+134450Y+018310X0280Y0320R180 S2      
327P52V_HS1         PC585 -2          A10X+135540Y+014950X0280Y0320R270 S2      
327P52V_HS1         PC581 -2          A10X+134500Y+013910X0280Y0320R180 S2      
317P52V_HS1         VIA   -    MD0100PA00X+131670Y+030690X0200Y         S0      
317P52V_HS1         VIA   -    MD0100PA00X+131370Y+030690X0200Y         S0      
317P52V_HS1         VIA   -    MD0100PA00X+131370Y+030990X0200Y         S0      
317P52V_HS1         VIA   -    MD0100PA00X+131070Y+030690X0200Y         S0      
317P52V_HS1         VIA   -    MD0100PA00X+131070Y+030990X0200Y         S0      
317P52V_HS1         VIA   -    MD0100PA00X+131070Y+031290X0200Y         S0      
317P52V_HS1         VIA   -    MD0100PA00X+130770Y+031290X0200Y         S0      
317P52V_HS1         VIA   -    MD0100PA00X+130770Y+030990X0200Y         S0      
317P52V_HS1         VIA   -    MD0100PA00X+130770Y+030690X0200Y         S0      
317P52V_HS1         VIA   -    MD0100PA00X+131970Y+030090X0200Y         S0      
317P52V_HS1         VIA   -    MD0100PA00X+131970Y+030390X0200Y         S0      
317P52V_HS1         VIA   -    MD0100PA00X+131670Y+030090X0200Y         S0      
317P52V_HS1         VIA   -    MD0100PA00X+131670Y+030390X0200Y         S0      
317P52V_HS1         VIA   -    MD0100PA00X+131370Y+030090X0200Y         S0      
317P52V_HS1         VIA   -    MD0100PA00X+131370Y+030390X0200Y         S0      
317P52V_HS1         VIA   -    MD0100PA00X+131070Y+030090X0200Y         S0      
317P52V_HS1         VIA   -    MD0100PA00X+131070Y+030390X0200Y         S0      
317P52V_HS1         VIA   -    MD0100PA00X+130770Y+030390X0200Y         S0      
317P52V_HS1         VIA   -    MD0100PA00X+130770Y+030090X0200Y         S0      
317P52V_HS1         VIA   -    MD0100PA00X+131970Y+026250X0200Y         S0      
317P52V_HS1         VIA   -    MD0100PA00X+131970Y+026550X0200Y         S0      
317P52V_HS1         VIA   -    MD0100PA00X+131970Y+026850X0200Y         S0      
317P52V_HS1         VIA   -    MD0100PA00X+131670Y+026250X0200Y         S0      
317P52V_HS1         VIA   -    MD0100PA00X+131670Y+026550X0200Y         S0      
317P52V_HS1         VIA   -    MD0100PA00X+131670Y+026850X0200Y         S0      
317P52V_HS1         VIA   -    MD0100PA00X+131370Y+026250X0200Y         S0      
317P52V_HS1         VIA   -    MD0100PA00X+131370Y+026550X0200Y         S0      
317P52V_HS1         VIA   -    MD0100PA00X+131370Y+026850X0200Y         S0      
317P52V_HS1         VIA   -    MD0100PA00X+131070Y+026250X0200Y         S0      
317P52V_HS1         VIA   -    MD0100PA00X+131070Y+026550X0200Y         S0      
317P52V_HS1         VIA   -    MD0100PA00X+131070Y+026850X0200Y         S0      
317P52V_HS1         VIA   -    MD0100PA00X+130770Y+026850X0200Y         S0      
317P52V_HS1         VIA   -    MD0100PA00X+130770Y+026550X0200Y         S0      
317P52V_HS1         VIA   -    MD0100PA00X+130770Y+026250X0200Y         S0      
317P52V_HS1         VIA   -    MD0100PA00X+131970Y+025650X0200Y         S0      
317P52V_HS1         VIA   -    MD0100PA00X+131970Y+025950X0200Y         S0      
317P52V_HS1         VIA   -    MD0100PA00X+131670Y+025650X0200Y         S0      
317P52V_HS1         VIA   -    MD0100PA00X+131670Y+025950X0200Y         S0      
317P52V_HS1         VIA   -    MD0100PA00X+131370Y+025650X0200Y         S0      
317P52V_HS1         VIA   -    MD0100PA00X+131370Y+025950X0200Y         S0      
317P52V_HS1         VIA   -    MD0100PA00X+131070Y+025650X0200Y         S0      
317P52V_HS1         VIA   -    MD0100PA00X+131070Y+025950X0200Y         S0      
317P52V_HS1         VIA   -    MD0100PA00X+130770Y+025950X0200Y         S0      
317P52V_HS1         VIA   -    MD0100PA00X+130770Y+025650X0200Y         S0      
317P52V_HS1         VIA   -    MD0100PA00X+131970Y+021810X0200Y         S0      
317P52V_HS1         VIA   -    MD0100PA00X+131970Y+022110X0200Y         S0      
317P52V_HS1         VIA   -    MD0100PA00X+131970Y+022410X0200Y         S0      
317P52V_HS1         VIA   -    MD0100PA00X+131670Y+021810X0200Y         S0      
317P52V_HS1         VIA   -    MD0100PA00X+131670Y+022110X0200Y         S0      
317P52V_HS1         VIA   -    MD0100PA00X+131670Y+022410X0200Y         S0      
317P52V_HS1         VIA   -    MD0100PA00X+131370Y+021810X0200Y         S0      
317P52V_HS1         VIA   -    MD0100PA00X+131370Y+022110X0200Y         S0      
317P52V_HS1         VIA   -    MD0100PA00X+131370Y+022410X0200Y         S0      
317P52V_HS1         VIA   -    MD0100PA00X+131070Y+021810X0200Y         S0      
317P52V_HS1         VIA   -    MD0100PA00X+131070Y+022110X0200Y         S0      
317P52V_HS1         VIA   -    MD0100PA00X+131070Y+022410X0200Y         S0      
317P52V_HS1         VIA   -    MD0100PA00X+130770Y+022410X0200Y         S0      
317P52V_HS1         VIA   -    MD0100PA00X+130770Y+022110X0200Y         S0      
317P52V_HS1         VIA   -    MD0100PA00X+130770Y+021810X0200Y         S0      
317P52V_HS1         VIA   -    MD0100PA00X+131970Y+021210X0200Y         S0      
317P52V_HS1         VIA   -    MD0100PA00X+131970Y+021510X0200Y         S0      
317P52V_HS1         VIA   -    MD0100PA00X+131670Y+021210X0200Y         S0      
317P52V_HS1         VIA   -    MD0100PA00X+131670Y+021510X0200Y         S0      
317P52V_HS1         VIA   -    MD0100PA00X+131370Y+021210X0200Y         S0      
317P52V_HS1         VIA   -    MD0100PA00X+131370Y+021510X0200Y         S0      
317P52V_HS1         VIA   -    MD0100PA00X+131070Y+021210X0200Y         S0      
317P52V_HS1         VIA   -    MD0100PA00X+131070Y+021510X0200Y         S0      
317P52V_HS1         VIA   -    MD0100PA00X+130770Y+021510X0200Y         S0      
317P52V_HS1         VIA   -    MD0100PA00X+130770Y+021210X0200Y         S0      
317P52V_HS1         VIA   -    MD0100PA00X+131970Y+008490X0200Y         S0      
317P52V_HS1         VIA   -    MD0100PA00X+131970Y+008790X0200Y         S0      
317P52V_HS1         VIA   -    MD0100PA00X+131970Y+009090X0200Y         S0      
317P52V_HS1         VIA   -    MD0100PA00X+131670Y+008490X0200Y         S0      
317P52V_HS1         VIA   -    MD0100PA00X+131670Y+008790X0200Y         S0      
317P52V_HS1         VIA   -    MD0100PA00X+131670Y+009090X0200Y         S0      
317P52V_HS1         VIA   -    MD0100PA00X+131370Y+008490X0200Y         S0      
317P52V_HS1         VIA   -    MD0100PA00X+131370Y+008790X0200Y         S0      
317P52V_HS1         VIA   -    MD0100PA00X+131370Y+009090X0200Y         S0      
317P52V_HS1         VIA   -    MD0100PA00X+131070Y+008490X0200Y         S0      
317P52V_HS1         VIA   -    MD0100PA00X+131070Y+008790X0200Y         S0      
317P52V_HS1         VIA   -    MD0100PA00X+131070Y+009090X0200Y         S0      
317P52V_HS1         VIA   -    MD0100PA00X+130770Y+009090X0200Y         S0      
317P52V_HS1         VIA   -    MD0100PA00X+130770Y+008790X0200Y         S0      
317P52V_HS1         VIA   -    MD0100PA00X+130770Y+008490X0200Y         S0      
317P52V_HS1         VIA   -    MD0100PA00X+131970Y+007890X0200Y         S0      
317P52V_HS1         VIA   -    MD0100PA00X+131970Y+008190X0200Y         S0      
317P52V_HS1         VIA   -    MD0100PA00X+131670Y+007890X0200Y         S0      
317P52V_HS1         VIA   -    MD0100PA00X+131670Y+008190X0200Y         S0      
317P52V_HS1         VIA   -    MD0100PA00X+131370Y+007890X0200Y         S0      
317P52V_HS1         VIA   -    MD0100PA00X+131370Y+008190X0200Y         S0      
317P52V_HS1         VIA   -    MD0100PA00X+131070Y+007890X0200Y         S0      
317P52V_HS1         VIA   -    MD0100PA00X+131070Y+008190X0200Y         S0      
317P52V_HS1         VIA   -    MD0100PA00X+130770Y+008190X0200Y         S0      
317P52V_HS1         VIA   -    MD0100PA00X+130770Y+007890X0200Y         S0      
317P52V_HS1         VIA   -    MD0100PA00X+131970Y+012930X0200Y         S0      
317P52V_HS1         VIA   -    MD0100PA00X+131970Y+013230X0200Y         S0      
317P52V_HS1         VIA   -    MD0100PA00X+131970Y+013530X0200Y         S0      
317P52V_HS1         VIA   -    MD0100PA00X+131670Y+012930X0200Y         S0      
317P52V_HS1         VIA   -    MD0100PA00X+131670Y+013230X0200Y         S0      
317P52V_HS1         VIA   -    MD0100PA00X+131670Y+013530X0200Y         S0      
317P52V_HS1         VIA   -    MD0100PA00X+131370Y+012930X0200Y         S0      
317P52V_HS1         VIA   -    MD0100PA00X+131370Y+013230X0200Y         S0      
317P52V_HS1         VIA   -    MD0100PA00X+131370Y+013530X0200Y         S0      
317P52V_HS1         VIA   -    MD0100PA00X+131070Y+012930X0200Y         S0      
317P52V_HS1         VIA   -    MD0100PA00X+131070Y+013230X0200Y         S0      
317P52V_HS1         VIA   -    MD0100PA00X+131070Y+013530X0200Y         S0      
317P52V_HS1         VIA   -    MD0100PA00X+130770Y+013530X0200Y         S0      
317P52V_HS1         VIA   -    MD0100PA00X+130770Y+013230X0200Y         S0      
317P52V_HS1         VIA   -    MD0100PA00X+130770Y+012930X0200Y         S0      
317P52V_HS1         VIA   -    MD0100PA00X+131970Y+012330X0200Y         S0      
317P52V_HS1         VIA   -    MD0100PA00X+131970Y+012630X0200Y         S0      
317P52V_HS1         VIA   -    MD0100PA00X+131670Y+012330X0200Y         S0      
317P52V_HS1         VIA   -    MD0100PA00X+131670Y+012630X0200Y         S0      
317P52V_HS1         VIA   -    MD0100PA00X+131370Y+012330X0200Y         S0      
317P52V_HS1         VIA   -    MD0100PA00X+131370Y+012630X0200Y         S0      
317P52V_HS1         VIA   -    MD0100PA00X+131070Y+012330X0200Y         S0      
317P52V_HS1         VIA   -    MD0100PA00X+131070Y+012630X0200Y         S0      
317P52V_HS1         VIA   -    MD0100PA00X+130770Y+012630X0200Y         S0      
317P52V_HS1         VIA   -    MD0100PA00X+130770Y+012330X0200Y         S0      
317P52V_HS1         VIA   -    MD0100PA00X+130770Y+016770X0200Y         S0      
317P52V_HS1         VIA   -    MD0100PA00X+130770Y+017070X0200Y         S0      
317P52V_HS1         VIA   -    MD0100PA00X+130770Y+017370X0200Y         S0      
317P52V_HS1         VIA   -    MD0100PA00X+130770Y+017670X0200Y         S0      
317P52V_HS1         VIA   -    MD0100PA00X+130770Y+017970X0200Y         S0      
317P52V_HS1         VIA   -    MD0100PA00X+131070Y+017970X0200Y         S0      
317P52V_HS1         VIA   -    MD0100PA00X+131070Y+017670X0200Y         S0      
317P52V_HS1         VIA   -    MD0100PA00X+131070Y+017370X0200Y         S0      
317P52V_HS1         VIA   -    MD0100PA00X+131070Y+017070X0200Y         S0      
317P52V_HS1         VIA   -    MD0100PA00X+131070Y+016770X0200Y         S0      
317P52V_HS1         VIA   -    MD0100PA00X+131370Y+017970X0200Y         S0      
317P52V_HS1         VIA   -    MD0100PA00X+131370Y+017670X0200Y         S0      
317P52V_HS1         VIA   -    MD0100PA00X+131370Y+017370X0200Y         S0      
317P52V_HS1         VIA   -    MD0100PA00X+131370Y+017070X0200Y         S0      
317P52V_HS1         VIA   -    MD0100PA00X+131370Y+016770X0200Y         S0      
317P52V_HS1         VIA   -    MD0100PA00X+131670Y+017670X0200Y         S0      
317P52V_HS1         VIA   -    MD0100PA00X+131670Y+017370X0200Y         S0      
317P52V_HS1         VIA   -    MD0100PA00X+131670Y+017070X0200Y         S0      
317P52V_HS1         VIA   -    MD0100PA00X+131670Y+016770X0200Y         S0      
317P52V_HS1         VIA   -    MD0100PA00X+131970Y+017670X0200Y         S0      
317P52V_HS1         VIA   -    MD0100PA00X+131970Y+017370X0200Y         S0      
317P52V_HS1         VIA   -    MD0100PA00X+131970Y+017070X0200Y         S0      
317P52V_HS1         VIA   -    MD0100PA00X+131970Y+016770X0200Y         S0      
317P52V_HS1         PC28  -1   MD0500PA00X+148850Y+055000X0700Y0700     S3      
317P52V_HS1         PC29  -1   MD0500PA00X+156550Y+055000X0700Y0700     S3      
317P52V_HS1         PC30  -1   MD0500PA00X+148850Y+047000X0700Y0700     S3      
317P52V_HS1         PC31  -1   MD0500PA00X+156550Y+047000X0700Y0700     S3      
317P52V_HS1         PC32  -1   MD0500PA00X+148850Y+039000X0700Y0700     S3      
317P52V_HS1         PC33  -1   MD0500PA00X+156550Y+039000X0700Y0700     S3      
317P52V_HS1         PC40  -1   MD0500PA00X+148850Y+031000X0700Y0700     S3      
317P52V_HS1         PC41  -1   MD0500PA00X+156550Y+031000X0700Y0700     S3      
317P52V_HS1         JP1   -P1_1MD0295PA00X+156841Y+066468X0455Y0455     S3      
317P52V_HS1         JP1   -P1_2MD0295PA00X+156841Y+065681X0455Y         S3      
317P52V_HS1         JP1   -P1_3MD0295PA00X+156841Y+064894X0455Y         S3      
317P52V_HS1         JP1   -P1_1MD0295PA00X+157628Y+066468X0455Y         S3      
317P52V_HS1         JP1   -P1_1MD0295PA00X+157628Y+065681X0455Y         S3      
317P52V_HS1         JP1   -P1_1MD0295PA00X+157628Y+064894X0455Y         S3      
317P52V_HS1         JP1   -P1_4MD0295PA00X+156841Y+064106X0455Y         S3      
317P52V_HS1         JP1   -P1_5MD0295PA00X+156841Y+063319X0455Y         S3      
317P52V_HS1         JP1   -P1_6MD0295PA00X+156841Y+062532X0455Y         S3      
317P52V_HS1         JP1   -P1_7MD0295PA00X+156841Y+061744X0455Y         S3      
317P52V_HS1         JP1   -P1_1MD0295PA00X+157628Y+064106X0455Y         S3      
317P52V_HS1         JP1   -P1_1MD0295PA00X+157628Y+063319X0455Y         S3      
317P52V_HS1         JP1   -P1_1MD0295PA00X+157628Y+062532X0455Y         S3      
317P52V_HS1         JP1   -P1_1MD0295PA00X+157628Y+061744X0455Y         S3      
317P52V_HS1         J1    -A1  MD0295PA00X+154016Y+061744X0455Y0455R180 S3      
317P52V_HS1         J1    -A2  MD0295PA00X+154016Y+062532X0455Y    R180 S3      
317P52V_HS1         J1    -A3  MD0295PA00X+154016Y+063319X0455Y    R180 S3      
317P52V_HS1         J1    -A4  MD0295PA00X+153228Y+061744X0455Y    R180 S3      
317P52V_HS1         J1    -A5  MD0295PA00X+153228Y+062532X0455Y    R180 S3      
317P52V_HS1         J1    -A6  MD0295PA00X+153228Y+063319X0455Y    R180 S3      
317P52V_HS1         J1    -B4  MD0295PA00X+151654Y+061744X0455Y    R180 S3      
317P52V_HS1         J1    -B5  MD0295PA00X+151654Y+062532X0455Y    R180 S3      
317P52V_HS1         J1    -B6  MD0295PA00X+151654Y+063319X0455Y    R180 S3      
317P52V_HS1         J1    -B1  MD0295PA00X+150866Y+061744X0455Y    R180 S3      
317P52V_HS1         J1    -B2  MD0295PA00X+150866Y+062532X0455Y    R180 S3      
317P52V_HS1         J1    -B3  MD0295PA00X+150866Y+063319X0455Y    R180 S3      
317P52V_HS1         J2    -A1  MD0295PA00X+148425Y+061744X0455Y0455R180 S3      
317P52V_HS1         J2    -A2  MD0295PA00X+148425Y+062532X0455Y    R180 S3      
317P52V_HS1         J2    -A3  MD0295PA00X+148425Y+063319X0455Y    R180 S3      
317P52V_HS1         J2    -A4  MD0295PA00X+147638Y+063319X0455Y    R180 S3      
317P52V_HS1         J2    -A5  MD0295PA00X+147638Y+062532X0455Y    R180 S3      
317P52V_HS1         J2    -A6  MD0295PA00X+147638Y+061744X0455Y    R180 S3      
317P52V_HS1         J2    -B5  MD0295PA00X+145276Y+062532X0455Y    R180 S3      
317P52V_HS1         J2    -B4  MD0295PA00X+145276Y+063319X0455Y    R180 S3      
317P52V_HS1         J2    -B3  MD0295PA00X+146063Y+063319X0455Y    R180 S3      
317P52V_HS1         J2    -B2  MD0295PA00X+146063Y+062532X0455Y    R180 S3      
317P52V_HS1         J2    -B6  MD0295PA00X+145276Y+061744X0455Y    R180 S3      
317P52V_HS1         J2    -B1  MD0295PA00X+146063Y+061744X0455Y    R180 S3      
317P52V_HS1         J2    -C5  MD0295PA00X+142913Y+062532X0455Y    R180 S3      
317P52V_HS1         J2    -C4  MD0295PA00X+142913Y+063319X0455Y    R180 S3      
317P52V_HS1         J2    -C3  MD0295PA00X+143701Y+063319X0455Y    R180 S3      
317P52V_HS1         J2    -C2  MD0295PA00X+143701Y+062532X0455Y    R180 S3      
317P52V_HS1         J2    -C6  MD0295PA00X+142913Y+061744X0455Y    R180 S3      
317P52V_HS1         J2    -C1  MD0295PA00X+143701Y+061744X0455Y    R180 S3      
317P52V_HS1         JP1   -P1_8MD0295PA00X+156841Y+060957X0455Y         S3      
317P52V_HS1         JP1   -P1_9MD0295PA00X+156841Y+060169X0455Y         S3      
317P52V_HS1         JP1   -P1_1MD0295PA00X+157628Y+060957X0455Y         S3      
317P52V_HS1         JP1   -P1_1MD0295PA00X+157628Y+060169X0455Y         S3      
317P52V_HS1         PC43  -1   MD0500PA00X+156550Y+023000X0700Y0700     S3      
317P52V_HS1         PC42  -1   MD0500PA00X+148850Y+023000X0700Y0700     S3      
327P52V_2           R5905 -1          A01X+059076Y+031800X0440Y0540R180 S1      
327P52V_2           PC595 -1          A10X+059488Y+031250X0460Y0620     S2      
327P52V_2           PU8   -10         A10X+059586Y+028949X0110Y0280R180 S2      
317P52V_2           VIA   -    MD0100PA00X+059068Y+031080X0200Y    R180 S0      
317P52V_2           VIA   -    MD0100PA00X+059068Y+031380X0200Y    R180 S0      
327P52V_2           PR7020-1          A10X+070660Y+022220X0400Y0630R270 S2      
317P52V_2           VIA   -    MD0100PA00X+058018Y+026000X0200Y    R180 S0      
317P52V_2           VIA   -    MD0100PA00X+058018Y+025700X0200Y    R180 S0      
317P52V_2           VIA   -    MD0100PA00X+058318Y+025700X0200Y    R180 S0      
317P52V_2           VIA   -    MD0100PA00X+058318Y+026000X0200Y    R180 S0      
317P52V_2           VIA   -    MD0100PA00X+058018Y+025400X0200Y    R180 S0      
317P52V_2           VIA   -    MD0100PA00X+058018Y+025100X0200Y    R180 S0      
317P52V_2           VIA   -    MD0100PA00X+058018Y+024800X0200Y    R180 S0      
317P52V_2           VIA   -    MD0100PA00X+058018Y+024500X0200Y    R180 S0      
317P52V_2           VIA   -    MD0100PA00X+058318Y+024500X0200Y    R180 S0      
317P52V_2           VIA   -    MD0100PA00X+058318Y+024800X0200Y    R180 S0      
317P52V_2           VIA   -    MD0100PA00X+058318Y+025100X0200Y    R180 S0      
317P52V_2           VIA   -    MD0100PA00X+058318Y+025400X0200Y    R180 S0      
317P52V_2           VIA   -    MD0100PA00X+058018Y+023900X0200Y    R180 S0      
317P52V_2           VIA   -    MD0100PA00X+058018Y+024200X0200Y    R180 S0      
317P52V_2           VIA   -    MD0100PA00X+058318Y+024200X0200Y    R180 S0      
317P52V_2           VIA   -    MD0100PA00X+058318Y+023900X0200Y    R180 S0      
317P52V_2           VIA   -    M      A01X+058018Y+010580X0200Y    R180 S2      
017P52V_2           VIA   -    M      A10X+058018Y+010580X0260Y    R180 S2      
017P52V_2                 -    MD0100PA00X+058018Y+010580                       
317P52V_2           VIA   -    MD0100PA00X+058318Y+010580X0200Y    R180 S0      
317P52V_2           VIA   -    MD0100PA00X+058618Y+010580X0200Y    R180 S0      
317P52V_2           VIA   -    MD0100PA00X+058018Y+010880X0200Y    R180 S0      
317P52V_2           VIA   -    MD0100PA00X+058318Y+010880X0200Y    R180 S0      
317P52V_2           VIA   -    MD0100PA00X+058618Y+010880X0200Y    R180 S0      
317P52V_2           VIA   -    MD0100PA00X+058018Y+011180X0200Y    R180 S0      
317P52V_2           VIA   -    MD0100PA00X+058318Y+011180X0200Y    R180 S0      
317P52V_2           VIA   -    M      A01X+058618Y+011180X0200Y    R180 S2      
017P52V_2           VIA   -    M      A10X+058618Y+011180X0260Y    R180 S2      
017P52V_2                 -    MD0100PA00X+058618Y+011180                       
317P52V_2           VIA   -    MD0100PA00X+058018Y+011480X0200Y    R180 S0      
317P52V_2           VIA   -    MD0100PA00X+058318Y+011480X0200Y    R180 S0      
317P52V_2           VIA   -    MD0100PA00X+058618Y+011480X0200Y    R180 S0      
317P52V_2           VIA   -    M      A01X+058018Y+011780X0200Y    R180 S2      
017P52V_2           VIA   -    M      A10X+058018Y+011780X0260Y    R180 S2      
017P52V_2                 -    MD0100PA00X+058018Y+011780                       
317P52V_2           VIA   -    MD0100PA00X+058318Y+011780X0200Y    R180 S0      
317P52V_2           VIA   -    MD0100PA00X+058618Y+011780X0200Y    R180 S0      
317P52V_2           VIA   -    MD0100PA00X+058018Y+012080X0200Y    R180 S0      
317P52V_2           VIA   -    MD0100PA00X+058318Y+012080X0200Y    R180 S0      
317P52V_2           VIA   -    MD0100PA00X+058618Y+012080X0200Y    R180 S0      
317P52V_2           VIA   -    MD0100PA00X+058018Y+012380X0200Y    R180 S0      
317P52V_2           VIA   -    MD0100PA00X+058318Y+012380X0200Y    R180 S0      
317P52V_2           VIA   -    MD0100PA00X+058618Y+012380X0200Y    R180 S0      
317P52V_2           VIA   -    MD0100PA00X+058618Y+012680X0200Y    R180 S0      
317P52V_2           VIA   -    MD0100PA00X+058318Y+012680X0200Y    R180 S0      
317P52V_2           VIA   -    MD0100PA00X+058018Y+012680X0200Y    R180 S0      
317P52V_2           VIA   -    MD0100PA00X+068798Y+021250X0200Y    R180 S0      
317P52V_2           VIA   -    MD0100PA00X+068548Y+021250X0200Y    R180 S0      
317P52V_2           VIA   -    MD0100PA00X+068198Y+021250X0200Y    R180 S0      
317P52V_2           VIA   -    MD0100PA00X+067948Y+021250X0200Y    R180 S0      
317P52V_2           VIA   -    MD0100PA00X+067498Y+021250X0200Y    R180 S0      
317P52V_2           VIA   -    MD0100PA00X+067248Y+021250X0200Y    R180 S0      
317P52V_2           VIA   -    MD0100PA00X+066698Y+021250X0200Y    R180 S0      
317P52V_2           VIA   -    MD0100PA00X+066448Y+021250X0200Y    R180 S0      
327P52V_2           PR6976-1A         A01X+057186Y+024950X1260Y2700     S1      
327P52V_2           PR6989-1A         A01X+057186Y+011630X1260Y2700     S1      
327P52V_2           PR6978-1          A10X+068968Y+021676X0440Y0540R090 S2      
327P52V_2           PR7019-1          A10X+068168Y+021676X0440Y0540R090 S2      
327P52V_2           PR6977-1          A10X+067368Y+021676X0440Y0540R090 S2      
327P52V_2           PR7023-1          A10X+066568Y+021676X0440Y0540R090 S2      
317P52V_2           VIA   -    MD0100PA00X+074255Y+013106X0200Y         S0      
317P52V_2           VIA   -    M      A01X+074255Y+012806X0300Y         S1      
017P52V_2           VIA   -    M      A10X+074255Y+012806X0200Y         S1      
017P52V_2                 -    MD0100PA00X+074255Y+012806                       
317P52V_2           VIA   -    MD0100PA00X+073955Y+012806X0200Y         S0      
317P52V_2           VIA   -    MD0100PA00X+073955Y+013106X0200Y         S0      
317P52V_2           VIA   -    MD0100PA00X+073655Y+012806X0200Y         S0      
317P52V_2           VIA   -    M      A01X+073655Y+013106X0300Y         S1      
017P52V_2           VIA   -    M      A10X+073655Y+013106X0200Y         S1      
017P52V_2                 -    MD0100PA00X+073655Y+013106                       
327P52V_2           FS6   -2          A10X+073960Y+014009X1280Y1350R090 S2      
317P52V_2           J7    -P2_2MD0402PA00X+080209Y+017098X0602Y    R180 S3      
317P52V_2           J7    -P2_3MD0402PA00X+081209Y+017098X0602Y    R180 S3      
317P52V_2           J7    -P2_4MD0402PA00X+082209Y+017098X0602Y    R180 S3      
317P52V_2           J7    -P2_6MD0402PA00X+080209Y+018098X0602Y    R180 S3      
317P52V_2           J7    -P2_7MD0402PA00X+081209Y+018098X0602Y    R180 S3      
317P52V_2           J7    -P2_8MD0402PA00X+082209Y+018098X0602Y    R180 S3      
317P52V_2           J7    -P2_1MD0402PA00X+079209Y+017098X0602Y    R180 S3      
317P52V_2           J7    -P2_5MD0402PA00X+079209Y+018098X0602Y    R180 S3      
317P52V_2           J7    -P1_2MD0402PA00X+080209Y+013598X0602Y    R180 S3      
317P52V_2           J7    -P1_3MD0402PA00X+081209Y+013598X0602Y    R180 S3      
317P52V_2           J7    -P1_4MD0402PA00X+082209Y+013598X0602Y    R180 S3      
317P52V_2           J7    -P1_6MD0402PA00X+080209Y+014598X0602Y    R180 S3      
317P52V_2           J7    -P1_7MD0402PA00X+081209Y+014598X0602Y    R180 S3      
317P52V_2           J7    -P1_8MD0402PA00X+082209Y+014598X0602Y    R180 S3      
317P52V_2           J7    -P1_1MD0402PA00X+079209Y+013598X0602Y    R180 S3      
317P52V_2           J7    -P1_5MD0402PA00X+079209Y+014598X0602Y    R180 S3      
327P52V_HS2         R5880 -1          A10X+069018Y+032024X0440Y0540R270 S2      
327P52V_HS2         PR7022-1          A10X+069918Y+032024X0440Y0540R270 S2      
317P52V_HS2         VIA   -    MD0100PA00X+069390Y+032403X0200Y         S0      
317P52V_HS2         VIA   -    MD0100PA00X+069661Y+032403X0200Y         S0      
327P52V_HS2         PC608 -1          A10X+072918Y+027420X0460Y0620R090 S2      
327P52V_HS2         PU9   -31         A10X+071423Y+027702X0120Y0330R270 S2      
317P52V_HS2         VIA   -    MD0100PA00X+072760Y+027000X0200Y         S0      
317P52V_HS2         VIA   -    MD0100PA00X+073060Y+027000X0200Y         S0      
317P52V_HS2         VIA   -    MD0100PA00X+065560Y+023770X0200Y    R180 S0      
317P52V_HS2         VIA   -    MD0100PA00X+065860Y+023770X0200Y    R180 S0      
327P52V_HS2         PR7024-1          A10X+065744Y+023350X0440Y0540     S2      
327P52V_HS2         PU8   -1          A10X+059320Y+026517X0110Y0280R270 S2      
327P52V_HS2         PR7004-1          A10X+059460Y+024376X0440Y0540R090 S2      
317P52V_HS2         VIA   -    MD0100PA00X+059248Y+023971X0200Y    R180 S0      
327P52V_HS2         PR7005-1          A10X+059386Y+023500X0440Y0540     S2      
317P52V_HS2         VIA   -    MD0100PA00X+059528Y+023971X0200Y    R180 S0      
327P52V_HS2         PC596 -2          A10X+040660Y+021400X0280Y0320R090 S2      
327P52V_HS2         PC594 -2          A10X+041750Y+020310X0280Y0320R180 S2      
327P52V_HS2         PC597 -2          A10X+041700Y+015910X0280Y0320R180 S2      
327P52V_HS2         PC598 -2          A10X+040660Y+016950X0280Y0320R090 S2      
327P52V_HS2         R162  -1          A01X+039454Y+005550X0440Y0540     S1      
327P52V_HS2         VIA   -           A01X+026300Y+014100X0300Y         S1      
327P52V_HS2         VIA   -           A01X+025400Y+014100X0300Y         S1      
327P52V_HS2         PQ38  -S          A01X+046234Y+028390X0520Y1220R270 S1      
327P52V_HS2         PQ39  -S          A01X+046234Y+023950X0520Y1220R270 S1      
327P52V_HS2         PQ40  -S          A01X+046234Y+019510X0520Y1220R270 S1      
327P52V_HS2         PQ41  -S          A01X+046234Y+015070X0520Y1220R270 S1      
327P52V_HS2         R39   -1          A01X+013958Y+016350X0400Y0630R180 S1      
327P52V_HS2         PD10  -C          A01X+023068Y+014239X0990Y1300R270 S1      
327P52V_HS2         PR104 -1          A01X+019260Y+014280X0400Y0630R270 S1      
327P52V_HS2         PQ16  -D          A01X+016678Y+014647X3327Y4173R090 S1      
327P52V_HS2         PQ42  -S          A01X+046234Y+010630X0520Y1220R270 S1      
327P52V_HS2         PQ43  -S          A01X+046234Y+006190X0520Y1220R270 S1      
317P52V_HS2         VIA   -    MD0100PA00X+044274Y+005600X0200Y    R180 S0      
317P52V_HS2         VIA   -    MD0100PA00X+044574Y+005600X0200Y    R180 S0      
317P52V_HS2         VIA   -    MD0100PA00X+044874Y+005600X0200Y    R180 S0      
317P52V_HS2         VIA   -    MD0100PA00X+045174Y+005600X0200Y    R180 S0      
317P52V_HS2         VIA   -    MD0100PA00X+045474Y+005600X0200Y    R180 S0      
317P52V_HS2         VIA   -    MD0100PA00X+044274Y+006800X0200Y    R180 S0      
317P52V_HS2         VIA   -    MD0100PA00X+044274Y+006500X0200Y    R180 S0      
317P52V_HS2         VIA   -    MD0100PA00X+044274Y+006200X0200Y    R180 S0      
317P52V_HS2         VIA   -    MD0100PA00X+044274Y+005900X0200Y    R180 S0      
317P52V_HS2         VIA   -    MD0100PA00X+044574Y+006800X0200Y    R180 S0      
317P52V_HS2         VIA   -    MD0100PA00X+044574Y+006500X0200Y    R180 S0      
317P52V_HS2         VIA   -    MD0100PA00X+044574Y+006200X0200Y    R180 S0      
317P52V_HS2         VIA   -    MD0100PA00X+044574Y+005900X0200Y    R180 S0      
317P52V_HS2         VIA   -    MD0100PA00X+044874Y+006800X0200Y    R180 S0      
317P52V_HS2         VIA   -    MD0100PA00X+044874Y+006500X0200Y    R180 S0      
317P52V_HS2         VIA   -    MD0100PA00X+044874Y+006200X0200Y    R180 S0      
317P52V_HS2         VIA   -    MD0100PA00X+044874Y+005900X0200Y    R180 S0      
317P52V_HS2         VIA   -    MD0100PA00X+045174Y+006800X0200Y    R180 S0      
317P52V_HS2         VIA   -    MD0100PA00X+045174Y+006500X0200Y    R180 S0      
317P52V_HS2         VIA   -    MD0100PA00X+045174Y+006200X0200Y    R180 S0      
317P52V_HS2         VIA   -    MD0100PA00X+045174Y+005900X0200Y    R180 S0      
317P52V_HS2         VIA   -    MD0100PA00X+045474Y+005900X0200Y    R180 S0      
317P52V_HS2         VIA   -    MD0100PA00X+045474Y+006200X0200Y    R180 S0      
317P52V_HS2         VIA   -    MD0100PA00X+045474Y+006500X0200Y    R180 S0      
317P52V_HS2         VIA   -    MD0100PA00X+045474Y+006800X0200Y    R180 S0      
317P52V_HS2         VIA   -    MD0100PA00X+044274Y+010040X0200Y    R180 S0      
317P52V_HS2         VIA   -    MD0100PA00X+044574Y+010040X0200Y    R180 S0      
317P52V_HS2         VIA   -    MD0100PA00X+044874Y+010040X0200Y    R180 S0      
317P52V_HS2         VIA   -    MD0100PA00X+045174Y+010040X0200Y    R180 S0      
317P52V_HS2         VIA   -    MD0100PA00X+045474Y+010040X0200Y    R180 S0      
317P52V_HS2         VIA   -    MD0100PA00X+044274Y+011240X0200Y    R180 S0      
317P52V_HS2         VIA   -    MD0100PA00X+044274Y+010940X0200Y    R180 S0      
317P52V_HS2         VIA   -    MD0100PA00X+044274Y+010640X0200Y    R180 S0      
317P52V_HS2         VIA   -    MD0100PA00X+044274Y+010340X0200Y    R180 S0      
317P52V_HS2         VIA   -    MD0100PA00X+044574Y+011240X0200Y    R180 S0      
317P52V_HS2         VIA   -    MD0100PA00X+044574Y+010940X0200Y    R180 S0      
317P52V_HS2         VIA   -    MD0100PA00X+044574Y+010640X0200Y    R180 S0      
317P52V_HS2         VIA   -    MD0100PA00X+044574Y+010340X0200Y    R180 S0      
317P52V_HS2         VIA   -    MD0100PA00X+044874Y+011240X0200Y    R180 S0      
317P52V_HS2         VIA   -    MD0100PA00X+044874Y+010940X0200Y    R180 S0      
317P52V_HS2         VIA   -    MD0100PA00X+044874Y+010640X0200Y    R180 S0      
317P52V_HS2         VIA   -    MD0100PA00X+044874Y+010340X0200Y    R180 S0      
317P52V_HS2         VIA   -    MD0100PA00X+045174Y+011240X0200Y    R180 S0      
317P52V_HS2         VIA   -    MD0100PA00X+045174Y+010940X0200Y    R180 S0      
317P52V_HS2         VIA   -    MD0100PA00X+045174Y+010640X0200Y    R180 S0      
317P52V_HS2         VIA   -    MD0100PA00X+045174Y+010340X0200Y    R180 S0      
317P52V_HS2         VIA   -    MD0100PA00X+045474Y+010340X0200Y    R180 S0      
317P52V_HS2         VIA   -    MD0100PA00X+045474Y+010640X0200Y    R180 S0      
317P52V_HS2         VIA   -    MD0100PA00X+045474Y+010940X0200Y    R180 S0      
317P52V_HS2         VIA   -    MD0100PA00X+045474Y+011240X0200Y    R180 S0      
317P52V_HS2         VIA   -    MD0100PA00X+044274Y+014480X0200Y    R180 S0      
317P52V_HS2         VIA   -    MD0100PA00X+044574Y+014480X0200Y    R180 S0      
317P52V_HS2         VIA   -    MD0100PA00X+044874Y+014480X0200Y    R180 S0      
317P52V_HS2         VIA   -    MD0100PA00X+045174Y+014480X0200Y    R180 S0      
317P52V_HS2         VIA   -    MD0100PA00X+045474Y+014480X0200Y    R180 S0      
317P52V_HS2         VIA   -    MD0100PA00X+044274Y+015680X0200Y    R180 S0      
317P52V_HS2         VIA   -    MD0100PA00X+044274Y+015380X0200Y    R180 S0      
317P52V_HS2         VIA   -    MD0100PA00X+044274Y+015080X0200Y    R180 S0      
317P52V_HS2         VIA   -    MD0100PA00X+044274Y+014780X0200Y    R180 S0      
317P52V_HS2         VIA   -    MD0100PA00X+044574Y+015680X0200Y    R180 S0      
317P52V_HS2         VIA   -    MD0100PA00X+044574Y+015380X0200Y    R180 S0      
317P52V_HS2         VIA   -    MD0100PA00X+044574Y+015080X0200Y    R180 S0      
317P52V_HS2         VIA   -    MD0100PA00X+044574Y+014780X0200Y    R180 S0      
317P52V_HS2         VIA   -    MD0100PA00X+044874Y+015680X0200Y    R180 S0      
317P52V_HS2         VIA   -    MD0100PA00X+044874Y+015380X0200Y    R180 S0      
317P52V_HS2         VIA   -    MD0100PA00X+044874Y+015080X0200Y    R180 S0      
317P52V_HS2         VIA   -    MD0100PA00X+044874Y+014780X0200Y    R180 S0      
317P52V_HS2         VIA   -    MD0100PA00X+045174Y+015680X0200Y    R180 S0      
317P52V_HS2         VIA   -    MD0100PA00X+045174Y+015380X0200Y    R180 S0      
317P52V_HS2         VIA   -    MD0100PA00X+045174Y+015080X0200Y    R180 S0      
317P52V_HS2         VIA   -    MD0100PA00X+045174Y+014780X0200Y    R180 S0      
317P52V_HS2         VIA   -    MD0100PA00X+045474Y+014780X0200Y    R180 S0      
317P52V_HS2         VIA   -    MD0100PA00X+045474Y+015080X0200Y    R180 S0      
317P52V_HS2         VIA   -    MD0100PA00X+045474Y+015380X0200Y    R180 S0      
317P52V_HS2         VIA   -    MD0100PA00X+045474Y+015680X0200Y    R180 S0      
317P52V_HS2         VIA   -    MD0100PA00X+044274Y+018920X0200Y    R180 S0      
317P52V_HS2         VIA   -    MD0100PA00X+044574Y+018920X0200Y    R180 S0      
317P52V_HS2         VIA   -    MD0100PA00X+044874Y+018920X0200Y    R180 S0      
317P52V_HS2         VIA   -    MD0100PA00X+045174Y+018920X0200Y    R180 S0      
317P52V_HS2         VIA   -    MD0100PA00X+045474Y+018920X0200Y    R180 S0      
317P52V_HS2         VIA   -    MD0100PA00X+044274Y+020120X0200Y    R180 S0      
317P52V_HS2         VIA   -    MD0100PA00X+044274Y+019820X0200Y    R180 S0      
317P52V_HS2         VIA   -    MD0100PA00X+044274Y+019520X0200Y    R180 S0      
317P52V_HS2         VIA   -    MD0100PA00X+044274Y+019220X0200Y    R180 S0      
317P52V_HS2         VIA   -    MD0100PA00X+044574Y+020120X0200Y    R180 S0      
317P52V_HS2         VIA   -    MD0100PA00X+044574Y+019820X0200Y    R180 S0      
317P52V_HS2         VIA   -    MD0100PA00X+044574Y+019520X0200Y    R180 S0      
317P52V_HS2         VIA   -    MD0100PA00X+044574Y+019220X0200Y    R180 S0      
317P52V_HS2         VIA   -    MD0100PA00X+044874Y+020120X0200Y    R180 S0      
317P52V_HS2         VIA   -    MD0100PA00X+044874Y+019820X0200Y    R180 S0      
317P52V_HS2         VIA   -    MD0100PA00X+044874Y+019520X0200Y    R180 S0      
317P52V_HS2         VIA   -    MD0100PA00X+044874Y+019220X0200Y    R180 S0      
317P52V_HS2         VIA   -    MD0100PA00X+045174Y+020120X0200Y    R180 S0      
317P52V_HS2         VIA   -    MD0100PA00X+045174Y+019820X0200Y    R180 S0      
317P52V_HS2         VIA   -    MD0100PA00X+045174Y+019520X0200Y    R180 S0      
317P52V_HS2         VIA   -    MD0100PA00X+045174Y+019220X0200Y    R180 S0      
317P52V_HS2         VIA   -    MD0100PA00X+045474Y+019220X0200Y    R180 S0      
317P52V_HS2         VIA   -    MD0100PA00X+045474Y+019520X0200Y    R180 S0      
317P52V_HS2         VIA   -    MD0100PA00X+045474Y+019820X0200Y    R180 S0      
317P52V_HS2         VIA   -    MD0100PA00X+045474Y+020120X0200Y    R180 S0      
317P52V_HS2         VIA   -    MD0100PA00X+044274Y+023360X0200Y    R180 S0      
317P52V_HS2         VIA   -    MD0100PA00X+044574Y+023360X0200Y    R180 S0      
317P52V_HS2         VIA   -    MD0100PA00X+044874Y+023360X0200Y    R180 S0      
317P52V_HS2         VIA   -    MD0100PA00X+045174Y+023360X0200Y    R180 S0      
317P52V_HS2         VIA   -    MD0100PA00X+045474Y+023360X0200Y    R180 S0      
317P52V_HS2         VIA   -    MD0100PA00X+044274Y+024560X0200Y    R180 S0      
317P52V_HS2         VIA   -    MD0100PA00X+044274Y+024260X0200Y    R180 S0      
317P52V_HS2         VIA   -    MD0100PA00X+044274Y+023960X0200Y    R180 S0      
317P52V_HS2         VIA   -    MD0100PA00X+044274Y+023660X0200Y    R180 S0      
317P52V_HS2         VIA   -    MD0100PA00X+044574Y+024560X0200Y    R180 S0      
317P52V_HS2         VIA   -    MD0100PA00X+044574Y+024260X0200Y    R180 S0      
317P52V_HS2         VIA   -    MD0100PA00X+044574Y+023960X0200Y    R180 S0      
317P52V_HS2         VIA   -    MD0100PA00X+044574Y+023660X0200Y    R180 S0      
317P52V_HS2         VIA   -    MD0100PA00X+044874Y+024560X0200Y    R180 S0      
317P52V_HS2         VIA   -    MD0100PA00X+044874Y+024260X0200Y    R180 S0      
317P52V_HS2         VIA   -    MD0100PA00X+044874Y+023960X0200Y    R180 S0      
317P52V_HS2         VIA   -    MD0100PA00X+044874Y+023660X0200Y    R180 S0      
317P52V_HS2         VIA   -    MD0100PA00X+045174Y+024560X0200Y    R180 S0      
317P52V_HS2         VIA   -    MD0100PA00X+045174Y+024260X0200Y    R180 S0      
317P52V_HS2         VIA   -    MD0100PA00X+045174Y+023960X0200Y    R180 S0      
317P52V_HS2         VIA   -    MD0100PA00X+045174Y+023660X0200Y    R180 S0      
317P52V_HS2         VIA   -    MD0100PA00X+045474Y+023660X0200Y    R180 S0      
317P52V_HS2         VIA   -    MD0100PA00X+045474Y+023960X0200Y    R180 S0      
317P52V_HS2         VIA   -    MD0100PA00X+045474Y+024260X0200Y    R180 S0      
317P52V_HS2         VIA   -    MD0100PA00X+045474Y+024560X0200Y    R180 S0      
317P52V_HS2         VIA   -    MD0100PA00X+044274Y+027800X0200Y    R180 S0      
317P52V_HS2         VIA   -    MD0100PA00X+044274Y+028100X0200Y    R180 S0      
317P52V_HS2         VIA   -    MD0100PA00X+044274Y+028400X0200Y    R180 S0      
317P52V_HS2         VIA   -    MD0100PA00X+044274Y+028700X0200Y    R180 S0      
317P52V_HS2         VIA   -    MD0100PA00X+044274Y+029000X0200Y    R180 S0      
317P52V_HS2         VIA   -    MD0100PA00X+044574Y+027800X0200Y    R180 S0      
317P52V_HS2         VIA   -    MD0100PA00X+044574Y+028100X0200Y    R180 S0      
317P52V_HS2         VIA   -    MD0100PA00X+044574Y+028400X0200Y    R180 S0      
317P52V_HS2         VIA   -    MD0100PA00X+044574Y+028700X0200Y    R180 S0      
317P52V_HS2         VIA   -    MD0100PA00X+044574Y+029000X0200Y    R180 S0      
317P52V_HS2         VIA   -    MD0100PA00X+045474Y+029000X0200Y    R180 S0      
317P52V_HS2         VIA   -    MD0100PA00X+045474Y+028700X0200Y    R180 S0      
317P52V_HS2         VIA   -    MD0100PA00X+045474Y+028400X0200Y    R180 S0      
317P52V_HS2         VIA   -    MD0100PA00X+045474Y+028100X0200Y    R180 S0      
317P52V_HS2         VIA   -    MD0100PA00X+045174Y+028100X0200Y    R180 S0      
317P52V_HS2         VIA   -    MD0100PA00X+045174Y+028400X0200Y    R180 S0      
317P52V_HS2         VIA   -    MD0100PA00X+045174Y+028700X0200Y    R180 S0      
317P52V_HS2         VIA   -    MD0100PA00X+045174Y+029000X0200Y    R180 S0      
317P52V_HS2         VIA   -    MD0100PA00X+044874Y+028100X0200Y    R180 S0      
317P52V_HS2         VIA   -    MD0100PA00X+044874Y+028400X0200Y    R180 S0      
317P52V_HS2         VIA   -    MD0100PA00X+044874Y+028700X0200Y    R180 S0      
317P52V_HS2         VIA   -    MD0100PA00X+044874Y+029000X0200Y    R180 S0      
317P52V_HS2         VIA   -    MD0100PA00X+045474Y+027800X0200Y    R180 S0      
317P52V_HS2         VIA   -    MD0100PA00X+045174Y+027800X0200Y    R180 S0      
317P52V_HS2         VIA   -    MD0100PA00X+044874Y+027800X0200Y    R180 S0      
317P52V_HS2         PC34  -1   MD0500PA00X+016678Y+055000X0700Y0700     S3      
317P52V_HS2         PC35  -1   MD0500PA00X+024378Y+055000X0700Y0700     S3      
317P52V_HS2         PC36  -1   MD0500PA00X+016678Y+047000X0700Y0700     S3      
317P52V_HS2         PC37  -1   MD0500PA00X+024378Y+047000X0700Y0700     S3      
317P52V_HS2         PC38  -1   MD0500PA00X+016678Y+039000X0700Y0700     S3      
317P52V_HS2         PC39  -1   MD0500PA00X+024378Y+039000X0700Y0700     S3      
317P52V_HS2         PC44  -1   MD0500PA00X+016678Y+031000X0700Y0700     S3      
317P52V_HS2         PC45  -1   MD0500PA00X+024378Y+031000X0700Y0700     S3      
317P52V_HS2         PC46  -1   MD0500PA00X+016678Y+023000X0700Y0700     S3      
317P52V_HS2         PC47  -1   MD0500PA00X+024378Y+023000X0700Y0700     S3      
317P52V_HS2         JP2   -P1_1MD0295PA00X+013730Y+066468X0455Y0455     S3      
317P52V_HS2         JP2   -P1_2MD0295PA00X+013730Y+065681X0455Y         S3      
317P52V_HS2         JP2   -P1_3MD0295PA00X+013730Y+064894X0455Y         S3      
317P52V_HS2         JP2   -P1_1MD0295PA00X+014518Y+066468X0455Y         S3      
317P52V_HS2         JP2   -P1_1MD0295PA00X+014518Y+065681X0455Y         S3      
317P52V_HS2         JP2   -P1_1MD0295PA00X+014518Y+064894X0455Y         S3      
317P52V_HS2         J4    -A1  MD0295PA00X+030315Y+061744X0455Y0455R180 S3      
317P52V_HS2         J4    -A2  MD0295PA00X+030315Y+062532X0455Y    R180 S3      
317P52V_HS2         J4    -A3  MD0295PA00X+030315Y+063319X0455Y    R180 S3      
317P52V_HS2         J4    -A4  MD0295PA00X+029528Y+063319X0455Y    R180 S3      
317P52V_HS2         J4    -A5  MD0295PA00X+029528Y+062532X0455Y    R180 S3      
317P52V_HS2         J4    -A6  MD0295PA00X+029528Y+061744X0455Y    R180 S3      
317P52V_HS2         J4    -B5  MD0295PA00X+027165Y+062532X0455Y    R180 S3      
317P52V_HS2         J4    -B4  MD0295PA00X+027165Y+063319X0455Y    R180 S3      
317P52V_HS2         J4    -B3  MD0295PA00X+027953Y+063319X0455Y    R180 S3      
317P52V_HS2         J4    -B2  MD0295PA00X+027953Y+062532X0455Y    R180 S3      
317P52V_HS2         J4    -B6  MD0295PA00X+027165Y+061744X0455Y    R180 S3      
317P52V_HS2         J4    -B1  MD0295PA00X+027953Y+061744X0455Y    R180 S3      
317P52V_HS2         J4    -C5  MD0295PA00X+024803Y+062532X0455Y    R180 S3      
317P52V_HS2         J4    -C4  MD0295PA00X+024803Y+063319X0455Y    R180 S3      
317P52V_HS2         J4    -C3  MD0295PA00X+025591Y+063319X0455Y    R180 S3      
317P52V_HS2         J4    -C2  MD0295PA00X+025591Y+062532X0455Y    R180 S3      
317P52V_HS2         J4    -C6  MD0295PA00X+024803Y+061744X0455Y    R180 S3      
317P52V_HS2         J4    -C1  MD0295PA00X+025591Y+061744X0455Y    R180 S3      
317P52V_HS2         J3    -A1  MD0295PA00X+022362Y+061744X0455Y0455R180 S3      
317P52V_HS2         J3    -A2  MD0295PA00X+022362Y+062532X0455Y    R180 S3      
317P52V_HS2         J3    -A3  MD0295PA00X+022362Y+063319X0455Y    R180 S3      
317P52V_HS2         J3    -A4  MD0295PA00X+021575Y+061744X0455Y    R180 S3      
317P52V_HS2         J3    -A5  MD0295PA00X+021575Y+062532X0455Y    R180 S3      
317P52V_HS2         J3    -A6  MD0295PA00X+021575Y+063319X0455Y    R180 S3      
317P52V_HS2         J3    -B4  MD0295PA00X+020000Y+061744X0455Y    R180 S3      
317P52V_HS2         J3    -B5  MD0295PA00X+020000Y+062532X0455Y    R180 S3      
317P52V_HS2         J3    -B6  MD0295PA00X+020000Y+063319X0455Y    R180 S3      
317P52V_HS2         J3    -B1  MD0295PA00X+019213Y+061744X0455Y    R180 S3      
317P52V_HS2         J3    -B2  MD0295PA00X+019213Y+062532X0455Y    R180 S3      
317P52V_HS2         J3    -B3  MD0295PA00X+019213Y+063319X0455Y    R180 S3      
317P52V_HS2         JP2   -P1_4MD0295PA00X+013730Y+064106X0455Y         S3      
317P52V_HS2         JP2   -P1_5MD0295PA00X+013730Y+063319X0455Y         S3      
317P52V_HS2         JP2   -P1_6MD0295PA00X+013730Y+062532X0455Y         S3      
317P52V_HS2         JP2   -P1_7MD0295PA00X+013730Y+061744X0455Y         S3      
317P52V_HS2         JP2   -P1_1MD0295PA00X+014518Y+064106X0455Y         S3      
317P52V_HS2         JP2   -P1_1MD0295PA00X+014518Y+063319X0455Y         S3      
317P52V_HS2         JP2   -P1_1MD0295PA00X+014518Y+062532X0455Y         S3      
317P52V_HS2         JP2   -P1_1MD0295PA00X+014518Y+061744X0455Y         S3      
317P52V_HS2         JP2   -P1_8MD0295PA00X+013730Y+060957X0455Y         S3      
317P52V_HS2         JP2   -P1_9MD0295PA00X+013730Y+060169X0455Y         S3      
317P52V_HS2         JP2   -P1_1MD0295PA00X+014518Y+060957X0455Y         S3      
317P52V_HS2         JP2   -P1_1MD0295PA00X+014518Y+060169X0455Y         S3      
317MB_P52V_I2C_EN   VIA   -    M      A01X+172610Y+015300X0200Y         S2      
017MB_P52V_I2C_EN   VIA   -    M      A10X+172610Y+015300X0260Y         S2      
017MB_P52V_I2C_EN         -    MD0100PA00X+172610Y+015300                       
327MB_P52V_I2C_EN   R10   -2          A01X+172108Y+015300X0198Y0197     S1      
327MB_P52V_I2C_EN   U2    -1          A01X+173371Y+015134X0140Y0560R270 S1      
327m0137            VIA   -    M      A01X+175860Y+014878X0300Y         S1      
327m0137            R9    -1   M      A01X+176850Y+014808X0198Y0197R270 S1      
327m0137            R12   -1          A01X+177300Y+014808X0198Y0197R270 S1      
327m0137            R14   -2   M      A01X+176400Y+014808X0198Y0197R090 S1      
327m0137            U2    -7          A01X+175129Y+014878X0140Y0560R270 S1      
327m0138            VIA   -    M      A01X+172610Y+014878X0300Y         S1      
327m0138            R8    -1   M      A01X+171710Y+014808X0198Y0197R270 S1      
327m0138            R11   -1          A01X+171160Y+014808X0198Y0197R270 S1      
327m0138            R13   -2   M      A01X+172100Y+014808X0198Y0197R090 S1      
327m0138            U2    -2          A01X+173371Y+014878X0140Y0560R270 S1      
317m0139            VIA   -    MD0100PA00X+113850Y+034750X0200Y         S0      
317m0139            VIA   -    M      A01X+171410Y+014492X0200Y         S2      
017m0139            VIA   -    M      A10X+171410Y+014492X0260Y         S2      
017m0139                  -    MD0100PA00X+171410Y+014492                       
327m0139            R11   -2          A01X+171160Y+014492X0198Y0197R270 S1      
327m0139            R81   -1          A10X+109768Y+027150X0198Y0197     S2      
317m0139            VIA   -    MD0100PA00X+110150Y+027150X0200Y         S0      
327m0139            R5869 -1          A10X+112402Y+028300X0198Y0197R180 S2      
317m0139            VIA   -    MD0100PA00X+112160Y+028300X0200Y         S0      
327m0139            R5886 -1          A10X+066461Y+028050X0198Y0197R180 S2      
317m0139            VIA   -    MD0100PA00X+066218Y+028050X0200Y    R180 S0      
317m0139            VIA   -    MD0100PA00X+064068Y+026900X0200Y    R180 S0      
327m0139            R5870 -1          A10X+063826Y+026900X0198Y0197     S2      
327m0139            PR473 -1          A01X+087818Y+036200X0198Y0197R180 S1      
317m0139            VIA   -    MD0100PA00X+087818Y+036471X0200Y         S0      
327m0140            R5856 -1          A10X+112402Y+029200X0198Y0197R180 S2      
327m0140            R5855 -1   M      A10X+112402Y+028750X0198Y0197R180 S2      
317m0140            VIA   -    MD0100PA00X+112160Y+028750X0200Y         S0      
327m0140            R147  -2   M      A10X+109452Y+026350X0198Y0197     S2      
317m0140            VIA   -    MD0100PA00X+109210Y+026350X0200Y         S0      
327m0140            R145  -1          A10X+109768Y+025550X0198Y0197     S2      
327m0140            R144  -1   M      A10X+109768Y+025950X0198Y0197     S2      
317m0140            VIA   -    MD0100PA00X+114150Y+034750X0200Y         S0      
317m0140            VIA   -    M      A01X+177300Y+014252X0200Y         S2      
017m0140            VIA   -    M      A10X+177300Y+014252X0260Y         S2      
017m0140                  -    MD0100PA00X+177300Y+014252                       
327m0140            R12   -2          A01X+177300Y+014492X0198Y0197R270 S1      
327m0140            R5883 -1          A10X+066461Y+029650X0198Y0197R180 S2      
327m0140            R5885 -2   M      A10X+066776Y+028850X0198Y0197R180 S2      
317m0140            VIA   -    MD0100PA00X+067018Y+028850X0200Y    R180 S0      
327m0140            R5882 -1   M      A10X+066461Y+029250X0198Y0197R180 S2      
327m0140            R5872 -1          A10X+063826Y+026000X0198Y0197     S2      
317m0140            VIA   -    MD0100PA00X+064068Y+026450X0200Y    R180 S0      
327m0140            R5871 -1   M      A10X+063826Y+026450X0198Y0197     S2      
327m0140            PR97  -1          A01X+087818Y+038200X0198Y0197R180 S1      
317m0140            VIA   -    MD0100PA00X+087818Y+037410X0200Y         S0      
317SMB_P52V_SDA     VIA   -    MD0100PA00X+185216Y+041924X0200Y    R090 S0      
327SMB_P52V_SDA     R87   -1          A01X+185216Y+042166X0198Y0197R090 S1      
327SMB_P52V_SDA     R14   -1   M      A01X+176400Y+014492X0198Y0197R090 S1      
317SMB_P52V_SDA     VIA   -    M      A01X+176400Y+014252X0200Y         S2      
017SMB_P52V_SDA     VIA   -    M      A10X+176400Y+014252X0260Y         S2      
017SMB_P52V_SDA           -    MD0100PA00X+176400Y+014252                       
327SMB_P52V_SDA     U2    -6          A01X+175129Y+014622X0140Y0560R270 S1      
317SMB_P52V_SCL     VIA   -    MD0100PA00X+183716Y+041924X0200Y    R090 S0      
327SMB_P52V_SCL     R86   -1          A01X+183716Y+042166X0198Y0197R090 S1      
327SMB_P52V_SCL     R13   -1   M      A01X+172100Y+014492X0198Y0197R090 S1      
317SMB_P52V_SCL     VIA   -    M      A01X+172100Y+014252X0200Y         S2      
017SMB_P52V_SCL     VIA   -    M      A10X+172100Y+014252X0260Y         S2      
017SMB_P52V_SCL           -    MD0100PA00X+172100Y+014252                       
327SMB_P52V_SCL     U2    -3          A01X+173371Y+014622X0140Y0560R270 S1      
327SMB_P52V_R_SCL   R86   -2          A01X+183716Y+042481X0198Y0197R090 S1      
317SMB_P52V_R_SCL   VIA   -    M      A01X+183716Y+042824X0200Y    R090 S2      
017SMB_P52V_R_SCL   VIA   -    M      A10X+183716Y+042824X0260Y    R090 S2      
017SMB_P52V_R_SCL         -    MD0100PA00X+183716Y+042824                       
317SMB_P52V_R_SCL   J11   -S6   D0410PA00X+185396Y+033921X0610Y    R090 S3      
317SMB_P52V_R_SDA   VIA   -    M      A01X+185216Y+043554X0200Y         S2      
017SMB_P52V_R_SDA   VIA   -    M      A10X+185216Y+043554X0260Y         S2      
017SMB_P52V_R_SDA         -    MD0100PA00X+185216Y+043554                       
327SMB_P52V_R_SDA   R87   -2          A01X+185216Y+042481X0198Y0197R090 S1      
317SMB_P52V_R_SDA   J11   -S5   D0410PA00X+185896Y+033421X0610Y    R090 S3      
327LED_D2_R5        VIA   -    M      A01X+012460Y+012050X0300Y         S1      
327LED_D2_R5        R47   -2          A01X+012699Y+012750X0400Y0630R180 S1      
327LED_D2_R5        D2    -A          A01X+013092Y+012050X0240Y0280     S1      
327LED_D1_R5        VIA   -    M      A01X+160710Y+011500X0300Y         S1      
327LED_D1_R5        R46   -2          A01X+160530Y+012200X0400Y0630     S1      
327LED_D1_R5        D1    -A          A01X+160137Y+011500X0240Y0280R180 S1      
317LED_D2_R4        VIA   -    M      A01X+013460Y+013400X0200Y         S2      
017LED_D2_R4        VIA   -    M      A10X+013460Y+013400X0260Y         S2      
017LED_D2_R4              -    MD0100PA00X+013460Y+013400                       
327LED_D2_R4        R45   -2          A01X+013958Y+013650X0400Y0630     S1      
327LED_D2_R4        R47   -1          A01X+013958Y+012750X0400Y0630R180 S1      
327LED_D2_R3        VIA   -    M      A01X+012084Y+014550X0300Y         S1      
327LED_D2_R3        R43   -2          A01X+012699Y+014550X0400Y0630R180 S1      
327LED_D2_R3        R45   -1          A01X+012699Y+013650X0400Y0630     S1      
327P52V_HS1_ADR1    PU1   -17         A10X+114674Y+026261X0110Y0300     S2      
317P52V_HS1_ADR1    VIA   -    MD0100PA00X+110810Y+028900X0200Y         S0      
327P52V_HS1_ADR1    R374  -1   M      A01X+110502Y+028500X0198Y0197     S1      
327P52V_HS1_ADR1    R372  -2   M      A01X+109552Y+028750X0198Y0197R180 S1      
317P52V_HS1_ADR1    VIA   -    MD0100PA00X+108560Y+027105X0200Y         S0      
327P52V_HS1_ADR1    PU7   -8          A10X+107915Y+027105X0120Y0330R090 S2      
317P52V_HS1_ADR1    VIA   -    M      A01X+114560Y+025750X0300Y         S1      
017P52V_HS1_ADR1    VIA   -    M      A10X+114560Y+025750X0200Y         S1      
017P52V_HS1_ADR1          -    MD0100PA00X+114560Y+025750                       
327P52V_HS1_ADR1    R159  -1          A10X+114560Y+024108X0198Y0197R090 S2      
327P52V_HS1_ADR1    R157  -2   M      A10X+114560Y+024958X0198Y0197R270 S2      
317LED_D2_R2        VIA   -    M      A01X+013460Y+015000X0200Y         S2      
017LED_D2_R2        VIA   -    M      A10X+013460Y+015000X0260Y         S2      
017LED_D2_R2              -    MD0100PA00X+013460Y+015000                       
327LED_D2_R2        R41   -2          A01X+013958Y+015450X0400Y0630     S1      
327LED_D2_R2        R43   -1          A01X+013958Y+014550X0400Y0630R180 S1      
327LED_D2_R1        VIA   -    M      A01X+012110Y+016350X0300Y         S1      
327LED_D2_R1        R39   -2          A01X+012699Y+016350X0400Y0630R180 S1      
327LED_D2_R1        R41   -1          A01X+012699Y+015450X0400Y0630     S1      
317LED_D1_R4        VIA   -    M      A01X+159710Y+012600X0200Y         S2      
017LED_D1_R4        VIA   -    M      A10X+159710Y+012600X0260Y         S2      
017LED_D1_R4              -    MD0100PA00X+159710Y+012600                       
327LED_D1_R4        R44   -2          A01X+159270Y+013100X0400Y0630R180 S1      
327LED_D1_R4        R46   -1          A01X+159270Y+012200X0400Y0630     S1      
327LED_D1_R3        VIA   -    M      A01X+161110Y+013850X0300Y         S1      
327LED_D1_R3        R42   -2          A01X+160530Y+014000X0400Y0630     S1      
327LED_D1_R3        R44   -1          A01X+160530Y+013100X0400Y0630R180 S1      
317LED_D1_R2        VIA   -    M      A01X+159710Y+014500X0200Y         S2      
017LED_D1_R2        VIA   -    M      A10X+159710Y+014500X0260Y         S2      
017LED_D1_R2              -    MD0100PA00X+159710Y+014500                       
327LED_D1_R2        R40   -2          A01X+159270Y+014900X0400Y0630R180 S1      
327LED_D1_R2        R42   -1          A01X+159270Y+014000X0400Y0630     S1      
327LED_D1_R1        VIA   -    M      A01X+161210Y+015400X0300Y         S1      
327LED_D1_R1        R38   -2          A01X+160530Y+015800X0400Y0630     S1      
327LED_D1_R1        R40   -1          A01X+160530Y+014900X0400Y0630R180 S1      
327MB_MISC_I2C_EN   VIA   -    M      A01X+172660Y+016850X0300Y         S1      
327MB_MISC_I2C_EN   R3    -2          A01X+172108Y+016850X0198Y0197     S1      
327MB_MISC_I2C_EN   U1    -1          A01X+173371Y+016684X0140Y0560R270 S1      
317GND_2_BUSBAR     J7    -B1   D0402PA00X+081209Y+020098X0602Y    R180 S3      
317SMB_PDB_SDA      VIA   -    M      A01X+184716Y+041924X0200Y    R090 S2      
017SMB_PDB_SDA      VIA   -    M      A10X+184716Y+041924X0260Y    R090 S2      
017SMB_PDB_SDA            -    MD0100PA00X+184716Y+041924                       
327SMB_PDB_SDA      R85   -1          A01X+184716Y+042166X0198Y0197R090 S1      
327SMB_PDB_SDA      R7    -1   M      A01X+176400Y+016042X0198Y0197R090 S1      
317SMB_PDB_SDA      VIA   -    MD0100PA00X+176400Y+015802X0200Y         S0      
327SMB_PDB_SDA      U1    -6          A01X+175129Y+016172X0140Y0560R270 S1      
317SMB_PDB_SCL      VIA   -    MD0100PA00X+184216Y+041924X0200Y    R090 S0      
327SMB_PDB_SCL      R84   -1          A01X+184216Y+042166X0198Y0197R090 S1      
327SMB_PDB_SCL      R6    -1   M      A01X+172100Y+016042X0198Y0197R090 S1      
317SMB_PDB_SCL      VIA   -    M      A01X+172206Y+015696X0200Y         S2      
017SMB_PDB_SCL      VIA   -    M      A10X+172206Y+015696X0260Y         S2      
017SMB_PDB_SCL            -    MD0100PA00X+172206Y+015696                       
327SMB_PDB_SCL      U1    -3          A01X+173371Y+016172X0140Y0560R270 S1      
317GND_1_BUSBAR     J6    -B1   D0402PA00X+093020Y+020098X0602Y    R180 S3      
327SMB_PDB_R_SDA    R85   -2          A01X+184716Y+042481X0198Y0197R090 S1      
317SMB_PDB_R_SDA    VIA   -    M      A01X+184716Y+043057X0200Y    R090 S2      
017SMB_PDB_R_SDA    VIA   -    M      A10X+184716Y+043057X0260Y    R090 S2      
017SMB_PDB_R_SDA          -    MD0100PA00X+184716Y+043057                       
317SMB_PDB_R_SDA    J11   -S7   D0410PA00X+185896Y+034421X0610Y    R090 S3      
327SMB_PDB_R_SCL    R84   -2          A01X+184216Y+042481X0198Y0197R090 S1      
317SMB_PDB_R_SCL    VIA   -    M      A01X+184216Y+043234X0200Y    R090 S2      
017SMB_PDB_R_SCL    VIA   -    M      A10X+184216Y+043234X0260Y    R090 S2      
017SMB_PDB_R_SCL          -    MD0100PA00X+184216Y+043234                       
317SMB_PDB_R_SCL    J11   -S8   D0410PA00X+185396Y+034921X0610Y    R090 S3      
317m0141            J11   -S15  D0410PA00X+184396Y+031921X0610Y    R090 S3      
317m0141            VIA   -    MD0100PA00X+173800Y+012450X0200Y         S0      
327m0141            U18   -3          A01X+173210Y+012450X0220Y0680R270 S1      
317m0141            VIA   -    M      A01X+149923Y+007450X0200Y         S2      
017m0141            VIA   -    M      A10X+149923Y+007450X0260Y         S2      
017m0141                  -    MD0100PA00X+149923Y+007450                       
327m0141            R74   -2          A01X+149923Y+007208X0198Y0197R090 S1      
327m0141            R78   -2          A01X+033050Y+007208X0198Y0197R090 S1      
317m0141            VIA   -    MD0100PA00X+033050Y+007448X0200Y         S0      
317GPU_HSC_BUF_EN   VIA   -    MD0100PA00X+104716Y+019744X0200Y         S0      
327GPU_HSC_BUF_EN   U22   -G          A01X+105084Y+019744X0320Y0360R180 S1      
317GPU_HSC_BUF_EN   VIA   -    MD0100PA00X+071943Y+032809X0200Y         S0      
317GPU_HSC_BUF_EN   VIA   -    M      A01X+177260Y+017730X0200Y         S2      
017GPU_HSC_BUF_EN   VIA   -    M      A10X+177260Y+017730X0260Y         S2      
017GPU_HSC_BUF_EN         -    MD0100PA00X+177260Y+017730                       
317GPU_HSC_BUF_EN   VIA   -    MD0100PA00X+102349Y+034659X0200Y         S0      
327GPU_HSC_BUF_EN   R186  -2   M      A01X+176692Y+017400X0198Y0197R180 S1      
327GPU_HSC_BUF_EN   R382  -2          A01X+176308Y+017400X0198Y0197     S1      
327GPU_HSC_BUF_EN   U23   -G          A01X+068216Y+019174X0320Y0360R270 S1      
317P52V_HS2_OV      VIA   -    M      A01X+067664Y+023089X0200Y         S2      
017P52V_HS2_OV      VIA   -    M      A10X+067664Y+023089X0260Y         S2      
017P52V_HS2_OV            -    MD0100PA00X+067664Y+023089                       
327P52V_HS2_OV      PR6977-2          A10X+067368Y+022424X0440Y0540R090 S2      
317P52V_HS2_OV      VIA   -    MD0100PA00X+068359Y+025991X0200Y    R180 S0      
327P52V_HS2_OV      PU9   -47         A10X+068785Y+026442X0120Y0330R180 S2      
327P52V_HS2_OV      PC577 -1          A10X+067610Y+025258X0198Y0197R090 S2      
327P52V_HS2_OV      PR6979-1   M      A10X+068010Y+025258X0198Y0197R090 S2      
327P52V_HS2_OV      PU8   -12         A10X+060570Y+028939X0110Y0300R180 S2      
317P52V_HS2_OV      VIA   -    MD0100PA00X+060293Y+029397X0200Y    R180 S0      
317SMB_IOEXP_SCL    VIA   -    M      A01X+168810Y+018422X0200Y         S2      
017SMB_IOEXP_SCL    VIA   -    M      A10X+168810Y+018422X0260Y         S2      
017SMB_IOEXP_SCL          -    MD0100PA00X+168810Y+018422                       
327SMB_IOEXP_SCL    R50   -2          A01X+169242Y+018650X0198Y0197R180 S1      
327SMB_IOEXP_SCL    U8    -22         A01X+166650Y+017596X0140Y0590R270 S1      
317SMB_IOEXP_SDA    VIA   -    M      A01X+167205Y+018155X0200Y         S2      
017SMB_IOEXP_SDA    VIA   -    M      A10X+167205Y+018155X0260Y         S2      
017SMB_IOEXP_SDA          -    MD0100PA00X+167205Y+018155                       
327SMB_IOEXP_SDA    R49   -2          A01X+168042Y+018650X0198Y0197R180 S1      
327SMB_IOEXP_SDA    U8    -23         A01X+166650Y+017852X0140Y0590R270 S1      
317m0142            VIA   -    MD0100PA00X+056301Y+024732X0200Y         S0      
327m0142            PR6976-1B         A01X+056606Y+024950X0100Y0200R180 S1      
327m0142            PR6981-2          A01X+057423Y+028250X0280Y0320R270 S1      
327m0142            PR6983-2   M      A01X+057423Y+027550X0280Y0320R270 S1      
327m0142            PR6985-2   M      A01X+057423Y+026850X0280Y0320R270 S1      
317m0142            VIA   -    MD0100PA00X+057647Y+026560X0200Y         S0      
317m0143            VIA   -    M      A01X+033250Y+006330X0200Y         S2      
017m0143            VIA   -    M      A10X+033250Y+006330X0260Y         S2      
017m0143                  -    MD0100PA00X+033250Y+006330                       
327m0143            R78   -1          A01X+033050Y+006892X0198Y0197R090 S1      
317m0143            J9    -S1   D0295PA00X+027465Y+000801X0455Y0455R270 S3      
317FAN_PWR_EN_1_R   VIA   -    M      A01X+032510Y+006400X0300Y         S1      
017FAN_PWR_EN_1_R   VIA   -    M      A10X+032510Y+006400X0200Y         S1      
017FAN_PWR_EN_1_R         -    MD0100PA00X+032510Y+006400                       
327FAN_PWR_EN_1_R   R76   -1          A01X+032600Y+006892X0198Y0197R090 S1      
317FAN_PWR_EN_1_R   J9    -S2   D0295PA00X+027965Y+001301X0455Y    R270 S3      
317m0144            VIA   -    MD0100PA00X+171908Y+011200X0200Y    R270 S0      
327m0144            U18   -5          A01X+173210Y+011450X0220Y0680R270 S1      
327m0144            R329  -1   M      A01X+171908Y+011450X0198Y0197R180 S1      
327m0144            R73   -1          A01X+149023Y+007208X0198Y0197R270 S1      
317m0144            VIA   -    M      A01X+149000Y+008050X0200Y         S2      
017m0144            VIA   -    M      A10X+149000Y+008050X0260Y         S2      
017m0144                  -    MD0100PA00X+149000Y+008050                       
317m0145            VIA   -    M      A01X+032150Y+006650X0200Y         S2      
017m0145            VIA   -    M      A10X+032150Y+006650X0260Y         S2      
017m0145                  -    MD0100PA00X+032150Y+006650                       
327m0145            R77   -2          A01X+032150Y+006892X0198Y0197R270 S1      
317m0145            J9    -S8   D0295PA00X+027465Y+001801X0455Y    R270 S3      
327P52V_HS2_ADR1    VIA   -    M      A01X+066676Y+027480X0300Y         S1      
317P52V_HS2_ADR1    VIA   -    MD0100PA00X+065410Y+026300X0200Y         S0      
327P52V_HS2_ADR1    PU9   -8          A10X+068313Y+028095X0120Y0330R270 S2      
317P52V_HS2_ADR1    VIA   -    MD0100PA00X+067668Y+028095X0200Y    R180 S0      
327P52V_HS2_ADR1    R5892 -2   M      A01X+066676Y+026450X0198Y0197     S1      
327P52V_HS2_ADR1    R5895 -1   M      A01X+065726Y+026600X0198Y0197R180 S1      
317P52V_HS2_ADR1    VIA   -    MD0100PA00X+061668Y+029450X0200Y         S0      
327P52V_HS2_ADR1    R5876 -1          A10X+061668Y+031092X0198Y0197R270 S2      
327P52V_HS2_ADR1    R5874 -2   M      A10X+061668Y+030242X0198Y0197R090 S2      
327P52V_HS2_ADR1    PU8   -17         A10X+061554Y+028939X0110Y0300R180 S2      
317m0146            VIA   -    M      A01X+031700Y+005800X0200Y         S2      
017m0146            VIA   -    M      A10X+031700Y+005800X0260Y         S2      
017m0146                  -    MD0100PA00X+031700Y+005800                       
317m0146            J9    -S7   D0295PA00X+027965Y+002301X0455Y    R270 S3      
317m0146            VIA   -    MD0100PA00X+031700Y+006450X0200Y         S0      
327m0146            R75   -2          A01X+031700Y+006892X0198Y0197R270 S1      
327m0147            R20   -2          A01X+176742Y+012450X0198Y0197R180 S1      
327m0147            U18   -12         A01X+175290Y+012450X0220Y0680R270 S1      
317m0147            VIA   -    M      A01X+176160Y+012452X0200Y         S2      
017m0147            VIA   -    M      A10X+176160Y+012452X0260Y         S2      
017m0147                  -    MD0100PA00X+176160Y+012452                       
327P52V_HS2_EN      PU9   -6          A10X+068313Y+027702X0120Y0330R270 S2      
317P52V_HS2_EN      VIA   -    MD0100PA00X+067368Y+028095X0200Y    R180 S0      
327P52V_HS2_EN      PU8   -23         A10X+062007Y+027895X0110Y0300R270 S2      
317P52V_HS2_EN      VIA   -    MD0100PA00X+062368Y+028100X0200Y    R180 S0      
317P52V_HS2_EN      VIA   -    MD0100PA00X+071090Y+032410X0200Y         S0      
317P52V_HS2_EN      VIA   -    MD0100PA00X+088526Y+038100X0200Y         S0      
327P52V_HS2_EN      PR103 -1          A01X+020800Y+010608X0198Y0197R270 S1      
317P52V_HS2_EN      VIA   -    M      A01X+021142Y+010608X0200Y         S2      
017P52V_HS2_EN      VIA   -    M      A10X+021142Y+010608X0260Y         S2      
017P52V_HS2_EN            -    MD0100PA00X+021142Y+010608                       
317P52V_HS2_EN      VIA   -    MD0100PA00X+086260Y+002950X0200Y         S0      
327P52V_HS2_EN      U35   -4          A01X+068372Y+031576X0220Y0320R270 S1      
327m0148            R331  -1   M      A01X+176742Y+010950X0198Y0197     S1      
317m0148            VIA   -    M      A01X+176742Y+010700X0200Y         S2      
017m0148            VIA   -    M      A10X+176742Y+010700X0260Y         S2      
017m0148                  -    MD0100PA00X+176742Y+010700                       
327m0148            U18   -9          A01X+175290Y+010950X0220Y0680R270 S1      
317m0148            VIA   -    MD0100PA00X+032150Y+007448X0200Y         S0      
327m0148            R77   -1          A01X+032150Y+007208X0198Y0197R270 S1      
327m0149            PR6982-2          A01X+055143Y+028250X0280Y0320R090 S1      
327m0149            PR6984-2   M      A01X+055143Y+027550X0280Y0320R090 S1      
327m0149            PR6986-2   M      A01X+055143Y+026850X0280Y0320R090 S1      
317m0149            VIA   -    MD0100PA00X+055143Y+026560X0200Y         S0      
317m0149            VIA   -    M      A01X+056301Y+025168X0200Y         S2      
017m0149            VIA   -    M      A10X+056301Y+025168X0260Y         S2      
017m0149                  -    MD0100PA00X+056301Y+025168                       
327m0149            PR6976-2B         A01X+055995Y+024950X0100Y0200R180 S1      
327m0150            VIA   -    M      A01X+176160Y+012950X0300Y         S1      
327m0150            R19   -2          A01X+176742Y+012950X0198Y0197R180 S1      
327m0150            U18   -13         A01X+175290Y+012950X0220Y0680R270 S1      
327PD_9543_FAN_A1   VIA   -    M      A01X+170808Y+012402X0300Y         S1      
327PD_9543_FAN_A1   R22   -2   M      A01X+171908Y+012950X0198Y0197     S1      
327PD_9543_FAN_A1   R24   -1          A01X+170808Y+012950X0198Y0197R180 S1      
327PD_9543_FAN_A1   U18   -2          A01X+173210Y+012950X0220Y0680R270 S1      
327PD_9543_FAN_A0   VIA   -    M      A01X+172460Y+013450X0300Y         S1      
327PD_9543_FAN_A0   R23   -2   M      A01X+171908Y+013450X0198Y0197     S1      
327PD_9543_FAN_A0   R25   -1          A01X+170808Y+013450X0198Y0197R180 S1      
327PD_9543_FAN_A0   U18   -1          A01X+173210Y+013450X0220Y0680R270 S1      
317m0151            VIA   -    M      A01X+171908Y+010702X0200Y    R270 S2      
017m0151            VIA   -    M      A10X+171908Y+010702X0260Y    R270 S2      
017m0151                  -    MD0100PA00X+171908Y+010702                       
327m0151            U18   -6          A01X+173210Y+010950X0220Y0680R270 S1      
327m0151            R328  -1   M      A01X+171908Y+010950X0198Y0197R180 S1      
327m0151            R71   -1          A01X+149473Y+007208X0198Y0197R270 S1      
317m0151            VIA   -    MD0100PA00X+149473Y+008350X0200Y         S0      
317m0152            JP3   -3    D0460PA00X+086640Y+036220X0660Y    R270 S3      
327m0152            PR473 -2          A01X+087502Y+036200X0198Y0197R180 S1      
317m0153            VIA   -    M      A01X+175960Y+011450X0200Y         S2      
017m0153            VIA   -    M      A10X+175960Y+011450X0260Y         S2      
017m0153                  -    MD0100PA00X+175960Y+011450                       
317m0153            VIA   -    MD0100PA00X+176752Y+011402X0200Y         S0      
327m0153            U18   -10         A01X+175290Y+011450X0220Y0680R270 S1      
327m0153            R330  -1   M      A01X+176752Y+011650X0198Y0197     S1      
317m0153            VIA   -    MD0100PA00X+031700Y+007448X0200Y         S0      
327m0153            R75   -1          A01X+031700Y+007208X0198Y0197R270 S1      
327m0154            PR97  -2          A01X+087502Y+038200X0198Y0197R180 S1      
317m0154            JP3   -1    D0460PA00X+086640Y+038220X0660Y0660R270 S3      
327m0155            VIA   -    M      A01X+162737Y+014350X0300Y         S1      
327m0155            U30   -D          A01X+163160Y+015694X0320Y0360     S1      
327m0155            R423  -1          A01X+163202Y+014200X0198Y0197     S1      
327m0156            R389  -2          A01X+170720Y+016358X0198Y0197R090 S1      
327m0156            R50   -1          A01X+169558Y+018650X0198Y0197R180 S1      
317m0156            VIA   -    M      A01X+170110Y+018200X0200Y         S2      
017m0156            VIA   -    M      A10X+170110Y+018200X0260Y         S2      
017m0156                  -    MD0100PA00X+170110Y+018200                       
327m0156            R5933 -1          A10X+168108Y+014550X0198Y0197     S2      
327m0157            U26   -G          A01X+173126Y+018806X0320Y0360     S1      
327m0157            R387  -2   M      A01X+172292Y+018350X0198Y0197R180 S1      
317m0157            J11   -S11  D0410PA00X+184396Y+033921X0610Y    R090 S3      
317m0157            VIA   -    MD0100PA00X+171552Y+015300X0200Y         S0      
327m0157            R10   -1          A01X+171792Y+015300X0198Y0197     S1      
327m0157            R3    -1          A01X+171792Y+016850X0198Y0197     S1      
317m0157            VIA   -    M      A01X+171552Y+016850X0200Y         S2      
017m0157            VIA   -    M      A10X+171552Y+016850X0260Y         S2      
017m0157                  -    MD0100PA00X+171552Y+016850                       
317m0157            VIA   -    MD0100PA00X+180010Y+018750X0200Y         S0      
327m0158            VIA   -    M      A01X+175860Y+016428X0300Y         S1      
327m0158            R2    -1   M      A01X+176850Y+016358X0198Y0197R270 S1      
327m0158            R5    -1          A01X+177300Y+016358X0198Y0197R270 S1      
327m0158            R7    -2   M      A01X+176400Y+016358X0198Y0197R090 S1      
327m0158            U1    -7          A01X+175129Y+016428X0140Y0560R270 S1      
317m0159            VIA   -    M      A01X+172710Y+016428X0200Y         S2      
017m0159            VIA   -    M      A10X+172710Y+016428X0260Y         S2      
017m0159                  -    MD0100PA00X+172710Y+016428                       
327m0159            R1    -1   M      A01X+171650Y+016358X0198Y0197R270 S1      
327m0159            R4    -1          A01X+171200Y+016358X0198Y0197R270 S1      
327m0159            R6    -2   M      A01X+172100Y+016358X0198Y0197R090 S1      
327m0159            U1    -2          A01X+173371Y+016428X0140Y0560R270 S1      
327P52V_HS2_VCAP    R5892 -1          A01X+066361Y+026450X0198Y0197     S1      
327P52V_HS2_VCAP    R5891 -1          A01X+066361Y+026050X0198Y0197     S1      
317P52V_HS2_VCAP    VIA   -    MD0100PA00X+066068Y+026250X0200Y    R180 S0      
327P52V_HS2_VCAP    PR7026-2          A10X+066311Y+026250X0198Y0197     S2      
317P52V_HS2_VCAP    VIA   -    M      A01X+067480Y+026960X0300Y         S1      
017P52V_HS2_VCAP    VIA   -    M      A10X+067480Y+026960X0200Y         S1      
017P52V_HS2_VCAP          -    MD0100PA00X+067480Y+026960                       
327P52V_HS2_VCAP    PR7027-2          A10X+067176Y+026900X0198Y0197R180 S2      
327P52V_HS2_VCAP    PC611 -1          A10X+067108Y+027400X0280Y0320R090 S2      
327P52V_HS2_VCAP    PU9   -3          A10X+068313Y+027111X0120Y0330R270 S2      
317m0160            VIA   -    M      A01X+177300Y+015800X0200Y         S2      
017m0160            VIA   -    M      A10X+177300Y+015800X0260Y         S2      
017m0160                  -    MD0100PA00X+177300Y+015800                       
327m0160            R5    -2          A01X+177300Y+016042X0198Y0197R270 S1      
327m0160            R19   -1          A01X+177058Y+012950X0198Y0197R180 S1      
317m0160            VIA   -    MD0100PA00X+170260Y+017150X0200Y         S0      
327m0160            R62   -2          A01X+170010Y+012498X0198Y0197R090 S1      
317m0160            VIA   -    MD0100PA00X+168598Y+018650X0200Y         S0      
327m0160            R49   -1          A01X+168358Y+018650X0198Y0197R180 S1      
327m0160            R5932 -1          A10X+168108Y+014150X0198Y0197     S2      
317P52V_HS2_ADR0    VIA   -    MD0100PA00X+065726Y+026300X0200Y         S0      
327P52V_HS2_ADR0    PU9   -7          A10X+068313Y+027898X0120Y0330R270 S2      
317P52V_HS2_ADR0    VIA   -    MD0100PA00X+067918Y+027898X0200Y    R180 S0      
327P52V_HS2_ADR0    R5891 -2   M      A01X+066676Y+026050X0198Y0197     S1      
327P52V_HS2_ADR0    R5894 -1   M      A01X+065726Y+026050X0198Y0197R180 S1      
317P52V_HS2_ADR0    VIA   -    M      A01X+061268Y+029700X0300Y         S1      
017P52V_HS2_ADR0    VIA   -    M      A10X+061268Y+029700X0200Y         S1      
017P52V_HS2_ADR0          -    MD0100PA00X+061268Y+029700                       
327P52V_HS2_ADR0    R5875 -1          A10X+061268Y+031092X0198Y0197R270 S2      
327P52V_HS2_ADR0    R5873 -2   M      A10X+061268Y+030242X0198Y0197R090 S2      
327P52V_HS2_ADR0    PU8   -16         A10X+061357Y+028939X0110Y0300R180 S2      
317m0161            J8    -S1   D0295PA00X+146520Y+000801X0455Y0455R270 S3      
317m0161            VIA   -    M      A01X+149818Y+006350X0300Y         S1      
017m0161            VIA   -    M      A10X+149818Y+006350X0200Y         S1      
017m0161                  -    MD0100PA00X+149818Y+006350                       
327m0161            R74   -1          A01X+149923Y+006893X0198Y0197R090 S1      
317P52V_FAN         J11   -P6  MD0410PA00X+185677Y+028043X0610Y    R090 S3      
317P52V_FAN         J11   -P7  MD0410PA00X+185677Y+029043X0610Y    R090 S3      
317P52V_FAN         J11   -P8  MD0410PA00X+185677Y+030043X0610Y    R090 S3      
317P52V_FAN         J11   -P5  MD0410PA00X+185677Y+027043X0610Y    R090 S3      
317P52V_FAN         J11   -P12 MD0410PA00X+184614Y+027043X0610Y    R090 S3      
317P52V_FAN         J11   -P11 MD0410PA00X+184614Y+028043X0610Y    R090 S3      
317P52V_FAN         J11   -P10 MD0410PA00X+184614Y+029043X0610Y    R090 S3      
317P52V_FAN         J11   -P9  MD0410PA00X+184614Y+030043X0610Y    R090 S3      
317P52V_FAN         VIA   -    MD0100PA00X+139723Y+002108X0200Y         S0      
317P52V_FAN         VIA   -    MD0100PA00X+139723Y+001808X0200Y         S0      
317P52V_FAN         VIA   -    MD0100PA00X+139723Y+001508X0200Y         S0      
317P52V_FAN         VIA   -    M      A01X+140023Y+001508X0300Y         S1      
017P52V_FAN         VIA   -    M      A10X+140023Y+001508X0200Y         S1      
017P52V_FAN               -    MD0100PA00X+140023Y+001508                       
317P52V_FAN         VIA   -    MD0100PA00X+140023Y+001808X0200Y         S0      
317P52V_FAN         VIA   -    M      A01X+140023Y+002108X0200Y         S2      
017P52V_FAN         VIA   -    M      A10X+140023Y+002108X0260Y         S2      
017P52V_FAN               -    MD0100PA00X+140023Y+002108                       
317P52V_FAN         VIA   -    MD0100PA00X+140323Y+001508X0200Y         S0      
317P52V_FAN         VIA   -    MD0100PA00X+140323Y+001808X0200Y         S0      
317P52V_FAN         VIA   -    MD0100PA00X+140323Y+002108X0200Y         S0      
317P52V_FAN         VIA   -    M      A01X+140623Y+001508X0200Y         S2      
017P52V_FAN         VIA   -    M      A10X+140623Y+001508X0260Y         S2      
017P52V_FAN               -    MD0100PA00X+140623Y+001508                       
317P52V_FAN         VIA   -    MD0100PA00X+140623Y+001808X0200Y         S0      
317P52V_FAN         VIA   -    M      A01X+140623Y+002108X0300Y         S1      
017P52V_FAN         VIA   -    M      A10X+140623Y+002108X0200Y         S1      
017P52V_FAN               -    MD0100PA00X+140623Y+002108                       
317P52V_FAN         VIA   -    MD0100PA00X+140923Y+001508X0200Y         S0      
317P52V_FAN         VIA   -    MD0100PA00X+140923Y+001808X0200Y         S0      
317P52V_FAN         VIA   -    MD0100PA00X+140923Y+002108X0200Y         S0      
317P52V_FAN         VIA   -    MD0100PA00X+141223Y+001508X0200Y         S0      
317P52V_FAN         VIA   -    MD0100PA00X+141223Y+001808X0200Y         S0      
317P52V_FAN         VIA   -    M      A01X+141223Y+002108X0200Y         S2      
017P52V_FAN         VIA   -    M      A10X+141223Y+002108X0260Y         S2      
017P52V_FAN               -    MD0100PA00X+141223Y+002108                       
317P52V_FAN         VIA   -    MD0100PA00X+032850Y+001500X0200Y         S0      
317P52V_FAN         VIA   -    MD0100PA00X+032850Y+001800X0200Y         S0      
317P52V_FAN         VIA   -    MD0100PA00X+032850Y+002100X0200Y         S0      
317P52V_FAN         VIA   -    MD0100PA00X+033150Y+001500X0200Y         S0      
317P52V_FAN         VIA   -    MD0100PA00X+033150Y+001800X0200Y         S0      
317P52V_FAN         VIA   -    MD0100PA00X+033150Y+002100X0200Y         S0      
317P52V_FAN         VIA   -    MD0100PA00X+033450Y+001500X0200Y         S0      
317P52V_FAN         VIA   -    MD0100PA00X+033450Y+001800X0200Y         S0      
317P52V_FAN         VIA   -    MD0100PA00X+033450Y+002100X0200Y         S0      
317P52V_FAN         VIA   -    MD0100PA00X+033750Y+001500X0200Y         S0      
317P52V_FAN         VIA   -    MD0100PA00X+033750Y+001800X0200Y         S0      
317P52V_FAN         VIA   -    MD0100PA00X+033750Y+002100X0200Y         S0      
317P52V_FAN         VIA   -    MD0100PA00X+034050Y+001500X0200Y         S0      
317P52V_FAN         VIA   -    MD0100PA00X+034050Y+001800X0200Y         S0      
317P52V_FAN         VIA   -    MD0100PA00X+034050Y+002100X0200Y         S0      
317P52V_FAN         VIA   -    MD0100PA00X+032550Y+002100X0200Y         S0      
317P52V_FAN         VIA   -    MD0100PA00X+032550Y+001800X0200Y         S0      
317P52V_FAN         VIA   -    MD0100PA00X+032550Y+001500X0200Y         S0      
317P52V_FAN         J8    -P2  MD0295PA00X+145142Y+001020X0455Y    R270 S3      
317P52V_FAN         J8    -P1  MD0295PA00X+144142Y+001020X0455Y    R270 S3      
317P52V_FAN         J9    -P1  MD0295PA00X+025087Y+001020X0455Y    R270 S3      
317P52V_FAN         J9    -P2  MD0295PA00X+026087Y+001020X0455Y    R270 S3      
327FRU_WP_N         VIA   -    M      A01X+169010Y+011600X0300Y    R090 S1      
327FRU_WP_N         R57   -2   M      A01X+169010Y+012182X0198Y0197R270 S1      
327FRU_WP_N         R58   -1          A01X+169010Y+013282X0198Y0197R090 S1      
327FRU_WP_N         U9    -7          A01X+169610Y+010730X0220Y0680     S1      
317FRU_ADDR2        VIA   -    M      A01X+170610Y+009200X0200Y         S2      
017FRU_ADDR2        VIA   -    M      A10X+170610Y+009200X0260Y         S2      
017FRU_ADDR2              -    MD0100PA00X+170610Y+009200                       
327FRU_ADDR2        R59   -2   M      A01X+171312Y+008800X0198Y0197R180 S1      
327FRU_ADDR2        R64   -2          A01X+172412Y+008800X0198Y0197R180 S1      
327FRU_ADDR2        U9    -3          A01X+170110Y+008650X0220Y0680     S1      
C                                                                               
C  ****************************************                                     
C      DUMMY NET PINS & VIAS ON THE BOARD                                       
C  ****************************************                                     
C                                                                               
327N/C              PU7   -35         A10X+104805Y+028286X0120Y0330R090 S2      
327N/C              PU9   -33         A10X+071423Y+027308X0120Y0330R270 S2      
327N/C              PU9   -27         A10X+071423Y+028489X0120Y0330R270 S2      
327N/C              PU9   -35         A10X+071423Y+026914X0120Y0330R270 S2      
327N/C              PU7   -26         A10X+104805Y+026514X0120Y0330R090 S2      
327N/C              PU9   -40         A10X+070557Y+026442X0120Y0330R180 S2      
327N/C              PU9   -36         A10X+071423Y+026717X0120Y0330R270 S2      
327N/C              PU9   -34         A10X+071423Y+027111X0120Y0330R270 S2      
327N/C              PU7   -40         A10X+105671Y+028758X0120Y0330     S2      
327N/C              PU7   -37         A10X+105080Y+028758X0120Y0330     S2      
327N/C              PU9   -26         A10X+071423Y+028686X0120Y0330R270 S2      
327N/C              PU7   -27         A10X+104805Y+026711X0120Y0330R090 S2      
327N/C              PU7   -25         A10X+104805Y+026317X0120Y0330R090 S2      
327N/C              PU7   -36         A10X+104805Y+028483X0120Y0330R090 S2      
327N/C              PU7   -28         A10X+104805Y+026908X0120Y0330R090 S2      
327N/C              PU9   -28         A10X+071423Y+028292X0120Y0330R270 S2      
327N/C              PU7   -34         A10X+104805Y+028089X0120Y0330R090 S2      
327N/C              PU7   -33         A10X+104805Y+027892X0120Y0330R090 S2      
327N/C              PU9   -37         A10X+071148Y+026442X0120Y0330R180 S2      
327N/C              PU9   -25         A10X+071423Y+028883X0120Y0330R270 S2      
327N/C                    -           A10X+059000Y+020850X0390Y         S2      
327N/C                    -           A01X+102489Y+023192X0390Y         S1      
327N/C                    -           A10X+128630Y+033140X0390Y         S2      
327N/C                    -           A10X+010242Y+060434X0390Y         S2      
327N/C                    -           A10X+171775Y+059962X0390Y         S2      
327N/C                    -           A01X+009915Y+060410X0390Y         S1      
327N/C                    -           A01X+164153Y+021981X0390Y         S1      
327N/C                    -           A01X+171693Y+050312X0390Y         S1      
317N/C              J9    -H1   D0950UA00X+030087Y+001020X0950Y    R270 S3      
317N/C              J9    -H2   D0950UA00X+024087Y+001551X0950Y    R270 S3      
317N/C              J8    -H1   D0950UA00X+149142Y+001020X0950Y    R270 S3      
317N/C              J8    -H2   D0950UA00X+143142Y+001551X0950Y    R270 S3      
317N/C              J7    -SCR_ D1260UA00X+082209Y+008848X2560Y2560R180 S3      
317N/C              J7    -SCR_ D1260UA00X+082209Y+031348X2560Y2560R180 S3      
317N/C              J6    -SCR_ D1260UA00X+094020Y+008848X2560Y2560R180 S3      
317N/C              J6    -SCR_ D1260UA00X+094020Y+031348X2560Y2560R180 S3      
317N/C              J4    -H1   D0850UA00X+028740Y+062846X0850Y    R180 S3      
317N/C              J4    -H2   D0850UA00X+026378Y+065996X0850Y    R180 S3      
317N/C              J2    -H1   D0850UA00X+146850Y+062846X0850Y    R180 S3      
317N/C              J2    -H2   D0850UA00X+144488Y+065996X0850Y    R180 S3      
317N/C              J3    -H1   D0830UA00X+020787Y+063910X0830Y    R180 S3      
317N/C              J1    -H1   D0830UA00X+152441Y+063910X0830Y    R180 S3      
317N/C              H27   -1    D1250UA00X+152910Y+007850X1250Y         S3      
317N/C              H26   -1    D1250UA00X+121248Y+030018X1250Y         S3      
317N/C              H25   -1    D1250UA00X+023160Y+008100X1250Y         S3      
317N/C              H24   -1    D1580UA00X+167323Y+023661X1580Y         S3      
317N/C              H23   -1    D1580UA00X+167323Y+041161X1580Y         S3      
317N/C              H22   -1    D1580UA00X+005906Y+023661X1580Y         S3      
317N/C              H21   -1    D1580UA00X+005906Y+041159X1580Y         S3      
317N/C              J11   -H1   D0860UA00X+185146Y+022043X0860Y    R090 S3      
317N/C              J11   -H2   D0860UA00X+185677Y+036043X0860Y    R090 S3      
327N/C              PU1   -18         A10X+114477Y+026251X0110Y0280     S2      
327N/C              PU1   -30         A10X+114211Y+028683X0110Y0280R090 S2      
327N/C              PU1   -31         A10X+114477Y+028949X0110Y0280     S2      
327N/C              PU1   -32         A10X+114674Y+028939X0110Y0300     S2      
327N/C              PU1   -22         A10X+114221Y+027108X0110Y0300R090 S2      
327N/C              PU9   -16         A10X+069179Y+029158X0120Y0330R180 S2      
327N/C              PU9   -15         A10X+068982Y+029158X0120Y0330R180 S2      
327N/C              PU7   -16         A10X+107049Y+026042X0120Y0330     S2      
327N/C              PU7   -15         A10X+107246Y+026042X0120Y0330     S2      
327N/C              PU8   -18         A10X+061751Y+028949X0110Y0280R180 S2      
327N/C              PU8   -30         A10X+062017Y+026517X0110Y0280R270 S2      
327N/C              PU8   -31         A10X+061751Y+026251X0110Y0280R180 S2      
327N/C              PU8   -32         A10X+061554Y+026261X0110Y0300R180 S2      
327N/C              PU8   -22         A10X+062007Y+028092X0110Y0300R270 S2      
327N/C              U45   -1          A01X+072556Y+031274X0170Y0240R180 S1      
327N/C              U44   -1          A01X+064394Y+031726X0170Y0240     S1      
327N/C              U43   -1          A10X+117094Y+036874X0170Y0240R180 S2      
327N/C              U42   -1          A10X+115026Y+033794X0170Y0240R270 S2      
C                                                                               
C  End-of-Job                                                                   
C                                                                               
999                                                                             
